FILE_TYPE = MACRO_DRAWING;
SET COLOR_WIRE YELLOW;
SET COLOR_PROP ORANGE;
SET COLOR_DOT WHITE;
SET COLOR_ARC YELLOW;
SET COLOR_BODY GREEN;
SET COLOR_NOTE PURPLE;
SET PROP_DISPLAY VALUE;
SET PAGE_NUMBER P318;
FORCEADD OFFPAGE..1
(-3300 -1100);
FORCEPROP 2 LAST $XR0 176 
J 0
(-3552 -1100);
DISPLAY 0.638298 (-3552 -1100);
PAINT MONO (-3552 -1100);
FORCEPROP 1 LAST OFFPAGE TRUE
J 0
(-2975 -1225);
DISPLAY 0.872340 (-2975 -1225);
PAINT AQUA (-2975 -1225);
DISPLAY INVISIBLE (-2975 -1225);
FORCEPROP 1 LAST COMMENT_BODY TRUE
J 0
(-3175 -1200);
DISPLAY 0.872340 (-3175 -1200);
PAINT GREEN (-3175 -1200);
DISPLAY INVISIBLE (-3175 -1200);
FORCEPROP 2 LAST CDS_LIB standard
J 0
(-3300 -1100);
DISPLAY INVISIBLE (-3300 -1100);
FORCEPROP 2 LAST PATH I1
J 0
(-3550 -1050);
DISPLAY 1.021277 (-3550 -1050);
DISPLAY INVISIBLE (-3550 -1050);
FORCEADD OFFPAGE..1
(-3300 -250);
FORCEPROP 2 LAST $XR0 176 
J 0
(-3552 -250);
DISPLAY 0.638298 (-3552 -250);
PAINT MONO (-3552 -250);
FORCEPROP 1 LAST OFFPAGE TRUE
J 0
(-2975 -375);
DISPLAY 0.872340 (-2975 -375);
PAINT AQUA (-2975 -375);
DISPLAY INVISIBLE (-2975 -375);
FORCEPROP 1 LAST COMMENT_BODY TRUE
J 0
(-3175 -350);
DISPLAY 0.872340 (-3175 -350);
PAINT GREEN (-3175 -350);
DISPLAY INVISIBLE (-3175 -350);
FORCEPROP 2 LAST CDS_LIB standard
J 0
(-3300 -250);
DISPLAY INVISIBLE (-3300 -250);
FORCEPROP 2 LAST PATH I11
J 0
(-3550 -200);
DISPLAY 1.021277 (-3550 -200);
DISPLAY INVISIBLE (-3550 -200);
FORCEADD OFFPAGE..1
(-3300 -200);
FORCEPROP 2 LAST $XR0 176 
J 0
(-3552 -200);
DISPLAY 0.638298 (-3552 -200);
PAINT MONO (-3552 -200);
FORCEPROP 1 LAST OFFPAGE TRUE
J 0
(-2975 -325);
DISPLAY 0.872340 (-2975 -325);
PAINT AQUA (-2975 -325);
DISPLAY INVISIBLE (-2975 -325);
FORCEPROP 1 LAST COMMENT_BODY TRUE
J 0
(-3175 -300);
DISPLAY 0.872340 (-3175 -300);
PAINT GREEN (-3175 -300);
DISPLAY INVISIBLE (-3175 -300);
FORCEPROP 2 LAST CDS_LIB standard
J 0
(-3300 -200);
DISPLAY INVISIBLE (-3300 -200);
FORCEPROP 2 LAST PATH I12
J 0
(-3550 -150);
DISPLAY 1.021277 (-3550 -150);
DISPLAY INVISIBLE (-3550 -150);
FORCEADD OFFPAGE..1
(-3300 -100);
FORCEPROP 2 LAST $XR0 177 
J 0
(-3552 -100);
DISPLAY 0.638298 (-3552 -100);
PAINT MONO (-3552 -100);
FORCEPROP 2 LAST CDS_LIB standard
J 0
(-3300 -100);
DISPLAY INVISIBLE (-3300 -100);
FORCEPROP 1 LAST COMMENT_BODY TRUE
J 0
(-3175 -200);
DISPLAY 0.872340 (-3175 -200);
PAINT GREEN (-3175 -200);
DISPLAY INVISIBLE (-3175 -200);
FORCEPROP 1 LAST OFFPAGE TRUE
J 0
(-2975 -225);
DISPLAY 0.872340 (-2975 -225);
PAINT AQUA (-2975 -225);
DISPLAY INVISIBLE (-2975 -225);
FORCEPROP 2 LAST PATH I13
J 0
(-3550 -50);
DISPLAY 1.021277 (-3550 -50);
DISPLAY INVISIBLE (-3550 -50);
FORCEADD OFFPAGE..1
(-3300 -50);
FORCEPROP 2 LAST $XR0 177 
J 0
(-3552 -50);
DISPLAY 0.638298 (-3552 -50);
PAINT MONO (-3552 -50);
FORCEPROP 2 LAST CDS_LIB standard
J 0
(-3300 -50);
DISPLAY INVISIBLE (-3300 -50);
FORCEPROP 1 LAST COMMENT_BODY TRUE
J 0
(-3175 -150);
DISPLAY 0.872340 (-3175 -150);
PAINT GREEN (-3175 -150);
DISPLAY INVISIBLE (-3175 -150);
FORCEPROP 1 LAST OFFPAGE TRUE
J 0
(-2975 -175);
DISPLAY 0.872340 (-2975 -175);
PAINT AQUA (-2975 -175);
DISPLAY INVISIBLE (-2975 -175);
FORCEPROP 2 LAST PATH I14
J 0
(-3550 0);
DISPLAY 1.021277 (-3550 0);
DISPLAY INVISIBLE (-3550 0);
FORCEADD UNIVERSAL_GND..1
(-2200 -1500);
FORCEPROP 3 LASTPIN (-2200 -1450) SIG_NAME GND\g
J 0
(-2190 -1440);
DISPLAY 0.659574 (-2190 -1440);
PAINT MONO (-2190 -1440);
DISPLAY INVISIBLE (-2190 -1440);
FORCEPROP 2 LAST CDS_LIB logical_power
J 0
(-2200 -1500);
DISPLAY INVISIBLE (-2200 -1500);
FORCEPROP 1 LAST HDL_POWER GND
J 1
(-2175 -1575);
DISPLAY 0.872340 (-2175 -1575);
PAINT GREEN (-2175 -1575);
DISPLAY INVISIBLE (-2175 -1575);
FORCEPROP 1 LAST PATH I15
J 0
(-2125 -1500);
DISPLAY 0.872340 (-2125 -1500);
PAINT AQUA (-2125 -1500);
DISPLAY INVISIBLE (-2125 -1500);
FORCEADD CONN112_10137002101LF..1
(-1100 400);
FORCEPROP 1 LAST PART_NUMBER DFHSB2FR012
J 0
(-1850 2150);
DISPLAY 0.723404 (-1850 2150);
PAINT GREEN (-1850 2150);
DISPLAY INVISIBLE (-1850 2150);
FORCEPROP 1 LAST MATERIAL IO
J 0
(-1845 2082);
DISPLAY 0.723404 (-1845 2082);
PAINT GREEN (-1845 2082);
FORCEPROP 2 LAST PART_TYPE THLF
J 0
(-1850 2275);
DISPLAY 1.021277 (-1850 2275);
FORCEPROP 1 LAST LOCATION J110
J 0
(-1850 2200);
DISPLAY 0.723404 (-1850 2200);
PAINT GREEN (-1850 2200);
FORCEPROP 0 LASTPIN (-2025 -500) $PN A5
J 2
(-2035 -490);
DISPLAY 0.680851 (-2035 -490);
PAINT MONO (-2035 -490);
FORCEPROP 0 LASTPIN (-2025 300) $PN A6
J 2
(-2035 310);
DISPLAY 0.680851 (-2035 310);
PAINT MONO (-2035 310);
FORCEPROP 0 LASTPIN (-2025 1100) $PN A7
J 2
(-2035 1110);
DISPLAY 0.680851 (-2035 1110);
PAINT MONO (-2035 1110);
FORCEPROP 0 LASTPIN (-2025 1900) $PN A8
J 2
(-2035 1910);
DISPLAY 0.680851 (-2035 1910);
PAINT MONO (-2035 1910);
FORCEPROP 0 LASTPIN (-2025 -550) $PN B5
J 2
(-2035 -540);
DISPLAY 0.680851 (-2035 -540);
PAINT MONO (-2035 -540);
FORCEPROP 0 LASTPIN (-2025 250) $PN B6
J 2
(-2035 260);
DISPLAY 0.680851 (-2035 260);
PAINT MONO (-2035 260);
FORCEPROP 0 LASTPIN (-2025 1050) $PN B7
J 2
(-2035 1060);
DISPLAY 0.680851 (-2035 1060);
PAINT MONO (-2035 1060);
FORCEPROP 0 LASTPIN (-2025 1850) $PN B8
J 2
(-2035 1860);
DISPLAY 0.680851 (-2035 1860);
PAINT MONO (-2035 1860);
FORCEPROP 0 LASTPIN (-2025 -600) $PN C5
J 2
(-2035 -590);
DISPLAY 0.680851 (-2035 -590);
PAINT MONO (-2035 -590);
FORCEPROP 0 LASTPIN (-2025 200) $PN C6
J 2
(-2035 210);
DISPLAY 0.680851 (-2035 210);
PAINT MONO (-2035 210);
FORCEPROP 0 LASTPIN (-2025 1000) $PN C7
J 2
(-2035 1010);
DISPLAY 0.680851 (-2035 1010);
PAINT MONO (-2035 1010);
FORCEPROP 0 LASTPIN (-2025 1800) $PN C8
J 2
(-2035 1810);
DISPLAY 0.680851 (-2035 1810);
PAINT MONO (-2035 1810);
FORCEPROP 0 LASTPIN (-2025 -650) $PN D5
J 2
(-2035 -640);
DISPLAY 0.680851 (-2035 -640);
PAINT MONO (-2035 -640);
FORCEPROP 0 LASTPIN (-2025 150) $PN D6
J 2
(-2035 160);
DISPLAY 0.680851 (-2035 160);
PAINT MONO (-2035 160);
FORCEPROP 0 LASTPIN (-2025 950) $PN D7
J 2
(-2035 960);
DISPLAY 0.680851 (-2035 960);
PAINT MONO (-2035 960);
FORCEPROP 0 LASTPIN (-2025 1750) $PN D8
J 2
(-2035 1760);
DISPLAY 0.680851 (-2035 1760);
PAINT MONO (-2035 1760);
FORCEPROP 0 LASTPIN (-2025 -700) $PN E5
J 2
(-2035 -690);
DISPLAY 0.680851 (-2035 -690);
PAINT MONO (-2035 -690);
FORCEPROP 0 LASTPIN (-2025 100) $PN E6
J 2
(-2035 110);
DISPLAY 0.680851 (-2035 110);
PAINT MONO (-2035 110);
FORCEPROP 0 LASTPIN (-2025 900) $PN E7
J 2
(-2035 910);
DISPLAY 0.680851 (-2035 910);
PAINT MONO (-2035 910);
FORCEPROP 0 LASTPIN (-2025 1700) $PN E8
J 2
(-2035 1710);
DISPLAY 0.680851 (-2035 1710);
PAINT MONO (-2035 1710);
FORCEPROP 0 LASTPIN (-2025 -750) $PN F5
J 2
(-2035 -740);
DISPLAY 0.680851 (-2035 -740);
PAINT MONO (-2035 -740);
FORCEPROP 0 LASTPIN (-2025 50) $PN F6
J 2
(-2035 60);
DISPLAY 0.680851 (-2035 60);
PAINT MONO (-2035 60);
FORCEPROP 0 LASTPIN (-2025 850) $PN F7
J 2
(-2035 860);
DISPLAY 0.680851 (-2035 860);
PAINT MONO (-2035 860);
FORCEPROP 0 LASTPIN (-2025 1650) $PN F8
J 2
(-2035 1660);
DISPLAY 0.680851 (-2035 1660);
PAINT MONO (-2035 1660);
FORCEPROP 0 LASTPIN (-2025 -800) $PN G5
J 2
(-2035 -790);
DISPLAY 0.680851 (-2035 -790);
PAINT MONO (-2035 -790);
FORCEPROP 0 LASTPIN (-2025 0) $PN G6
J 2
(-2035 10);
DISPLAY 0.680851 (-2035 10);
PAINT MONO (-2035 10);
FORCEPROP 0 LASTPIN (-2025 800) $PN G7
J 2
(-2035 810);
DISPLAY 0.680851 (-2035 810);
PAINT MONO (-2035 810);
FORCEPROP 0 LASTPIN (-2025 1600) $PN G8
J 2
(-2035 1610);
DISPLAY 0.680851 (-2035 1610);
PAINT MONO (-2035 1610);
FORCEPROP 0 LASTPIN (-2025 -850) $PN H5
J 2
(-2035 -840);
DISPLAY 0.680851 (-2035 -840);
PAINT MONO (-2035 -840);
FORCEPROP 0 LASTPIN (-2025 -50) $PN H6
J 2
(-2035 -40);
DISPLAY 0.680851 (-2035 -40);
PAINT MONO (-2035 -40);
FORCEPROP 0 LASTPIN (-2025 750) $PN H7
J 2
(-2035 760);
DISPLAY 0.680851 (-2035 760);
PAINT MONO (-2035 760);
FORCEPROP 0 LASTPIN (-2025 1550) $PN H8
J 2
(-2035 1560);
DISPLAY 0.680851 (-2035 1560);
PAINT MONO (-2035 1560);
FORCEPROP 0 LASTPIN (-2025 -900) $PN I5
J 2
(-2035 -890);
DISPLAY 0.680851 (-2035 -890);
PAINT MONO (-2035 -890);
FORCEPROP 0 LASTPIN (-2025 -100) $PN I6
J 2
(-2035 -90);
DISPLAY 0.680851 (-2035 -90);
PAINT MONO (-2035 -90);
FORCEPROP 0 LASTPIN (-2025 700) $PN I7
J 2
(-2035 710);
DISPLAY 0.680851 (-2035 710);
PAINT MONO (-2035 710);
FORCEPROP 0 LASTPIN (-2025 1500) $PN I8
J 2
(-2035 1510);
DISPLAY 0.680851 (-2035 1510);
PAINT MONO (-2035 1510);
FORCEPROP 0 LASTPIN (-2025 -950) $PN J5
J 2
(-2035 -940);
DISPLAY 0.680851 (-2035 -940);
PAINT MONO (-2035 -940);
FORCEPROP 0 LASTPIN (-2025 -150) $PN J6
J 2
(-2035 -140);
DISPLAY 0.680851 (-2035 -140);
PAINT MONO (-2035 -140);
FORCEPROP 0 LASTPIN (-2025 650) $PN J7
J 2
(-2035 660);
DISPLAY 0.680851 (-2035 660);
PAINT MONO (-2035 660);
FORCEPROP 0 LASTPIN (-2025 1450) $PN J8
J 2
(-2035 1460);
DISPLAY 0.680851 (-2035 1460);
PAINT MONO (-2035 1460);
FORCEPROP 0 LASTPIN (-2025 -1000) $PN K5
J 2
(-2035 -990);
DISPLAY 0.680851 (-2035 -990);
PAINT MONO (-2035 -990);
FORCEPROP 0 LASTPIN (-2025 -200) $PN K6
J 2
(-2035 -190);
DISPLAY 0.680851 (-2035 -190);
PAINT MONO (-2035 -190);
FORCEPROP 0 LASTPIN (-2025 600) $PN K7
J 2
(-2035 610);
DISPLAY 0.680851 (-2035 610);
PAINT MONO (-2035 610);
FORCEPROP 0 LASTPIN (-2025 1400) $PN K8
J 2
(-2035 1410);
DISPLAY 0.680851 (-2035 1410);
PAINT MONO (-2035 1410);
FORCEPROP 0 LASTPIN (-2025 -1050) $PN L5
J 2
(-2035 -1040);
DISPLAY 0.680851 (-2035 -1040);
PAINT MONO (-2035 -1040);
FORCEPROP 0 LASTPIN (-2025 -250) $PN L6
J 2
(-2035 -240);
DISPLAY 0.680851 (-2035 -240);
PAINT MONO (-2035 -240);
FORCEPROP 0 LASTPIN (-2025 550) $PN L7
J 2
(-2035 560);
DISPLAY 0.680851 (-2035 560);
PAINT MONO (-2035 560);
FORCEPROP 0 LASTPIN (-2025 1350) $PN L8
J 2
(-2035 1360);
DISPLAY 0.680851 (-2035 1360);
PAINT MONO (-2035 1360);
FORCEPROP 0 LASTPIN (-2025 -1100) $PN M5
J 2
(-2035 -1090);
DISPLAY 0.680851 (-2035 -1090);
PAINT MONO (-2035 -1090);
FORCEPROP 0 LASTPIN (-2025 -300) $PN M6
J 2
(-2035 -290);
DISPLAY 0.680851 (-2035 -290);
PAINT MONO (-2035 -290);
FORCEPROP 0 LASTPIN (-2025 500) $PN M7
J 2
(-2035 510);
DISPLAY 0.680851 (-2035 510);
PAINT MONO (-2035 510);
FORCEPROP 0 LASTPIN (-2025 1300) $PN M8
J 2
(-2035 1310);
DISPLAY 0.680851 (-2035 1310);
PAINT MONO (-2035 1310);
FORCEPROP 0 LASTPIN (-2025 -1150) $PN N5
J 2
(-2035 -1140);
DISPLAY 0.680851 (-2035 -1140);
PAINT MONO (-2035 -1140);
FORCEPROP 0 LASTPIN (-2025 -350) $PN N6
J 2
(-2035 -340);
DISPLAY 0.680851 (-2035 -340);
PAINT MONO (-2035 -340);
FORCEPROP 0 LASTPIN (-2025 450) $PN N7
J 2
(-2035 460);
DISPLAY 0.680851 (-2035 460);
PAINT MONO (-2035 460);
FORCEPROP 0 LASTPIN (-2025 1250) $PN N8
J 2
(-2035 1260);
DISPLAY 0.680851 (-2035 1260);
PAINT MONO (-2035 1260);
FORCEPROP 2 LAST CDS_LIB pure_quanta
J 0
(-1100 400);
DISPLAY INVISIBLE (-1100 400);
FORCEPROP 1 LAST NEEDS_NO_SIZE TRUE
J 0
(-1100 400);
DISPLAY 0.723404 (-1100 400);
PAINT GREEN (-1100 400);
DISPLAY INVISIBLE (-1100 400);
FORCEPROP 1 LAST CDS_LMAN_SYM_OUTLINE -775,1650,775,-1650
J 0
(-1100 400);
DISPLAY 0.468085 (-1100 400);
PAINT GREEN (-1100 400);
DISPLAY INVISIBLE (-1100 400);
FORCEPROP 0 LAST VALUE CONN112_10137002-101LF
J 0
(-1825 2400);
DISPLAY 1.021277 (-1825 2400);
DISPLAY INVISIBLE (-1825 2400);
FORCEPROP 1 LAST PATH I16
J 0
(-1100 400);
DISPLAY 0.723404 (-1100 400);
PAINT GREEN (-1100 400);
DISPLAY INVISIBLE (-1100 400);
FORCEPROP 0 LAST $SEC 1
J 0
(-1850 2325);
DISPLAY 0.680851 (-1850 2325);
PAINT MONO (-1850 2325);
DISPLAY INVISIBLE (-1850 2325);
FORCEPROP 0 LAST CDS_SEC 1
J 0
(-1850 2325);
DISPLAY 1.021277 (-1850 2325);
DISPLAY INVISIBLE (-1850 2325);
FORCEADD OFFPAGE..2
R 2
(-3300 100);
FORCEPROP 2 LAST $XR0 61 
J 0
(-3554 100);
DISPLAY 0.638298 (-3554 100);
PAINT MONO (-3554 100);
FORCEPROP 1 LAST OFFPAGE TRUE
J 2
(-3625 -25);
DISPLAY 0.872340 (-3625 -25);
PAINT AQUA (-3625 -25);
DISPLAY INVISIBLE (-3625 -25);
FORCEPROP 1 LAST COMMENT_BODY TRUE
J 2
(-3255 5);
DISPLAY 0.872340 (-3255 5);
PAINT GREEN (-3255 5);
DISPLAY INVISIBLE (-3255 5);
FORCEPROP 2 LAST CDS_LIB standard
J 0
(-3300 100);
DISPLAY INVISIBLE (-3300 100);
FORCEPROP 2 LAST PATH I17
J 0
(-3550 150);
DISPLAY 1.021277 (-3550 150);
DISPLAY INVISIBLE (-3550 150);
FORCEADD OFFPAGE..5
(-3300 50);
FORCEPROP 2 LAST $XR0 61 
J 0
(-3554 50);
DISPLAY 0.638298 (-3554 50);
PAINT MONO (-3554 50);
FORCEPROP 1 LAST OFFPAGE TRUE
J 0
(-2975 -75);
DISPLAY 0.872340 (-2975 -75);
PAINT AQUA (-2975 -75);
DISPLAY INVISIBLE (-2975 -75);
FORCEPROP 1 LAST COMMENT_BODY TRUE
J 0
(-3200 -25);
DISPLAY 1.170213 (-3200 -25);
PAINT GREEN (-3200 -25);
DISPLAY INVISIBLE (-3200 -25);
FORCEPROP 2 LAST CDS_LIB standard
J 0
(-3300 50);
DISPLAY INVISIBLE (-3300 50);
FORCEPROP 2 LAST PATH I18
J 0
(-3550 100);
DISPLAY 1.021277 (-3550 100);
DISPLAY INVISIBLE (-3550 100);
FORCEADD OFFPAGE..5
(-3300 200);
FORCEPROP 2 LAST $XR0 61 
J 0
(-3554 200);
DISPLAY 0.638298 (-3554 200);
PAINT MONO (-3554 200);
FORCEPROP 1 LAST OFFPAGE TRUE
J 0
(-2975 75);
DISPLAY 0.872340 (-2975 75);
PAINT AQUA (-2975 75);
DISPLAY INVISIBLE (-2975 75);
FORCEPROP 1 LAST COMMENT_BODY TRUE
J 0
(-3200 125);
DISPLAY 1.170213 (-3200 125);
PAINT GREEN (-3200 125);
DISPLAY INVISIBLE (-3200 125);
FORCEPROP 2 LAST CDS_LIB standard
J 0
(-3300 200);
DISPLAY INVISIBLE (-3300 200);
FORCEPROP 2 LAST PATH I19
J 0
(-3550 250);
DISPLAY 1.021277 (-3550 250);
DISPLAY INVISIBLE (-3550 250);
FORCEADD OFFPAGE..1
(-3300 -1050);
FORCEPROP 2 LAST $XR0 176 
J 0
(-3552 -1050);
DISPLAY 0.638298 (-3552 -1050);
PAINT MONO (-3552 -1050);
FORCEPROP 1 LAST OFFPAGE TRUE
J 0
(-2975 -1175);
DISPLAY 0.872340 (-2975 -1175);
PAINT AQUA (-2975 -1175);
DISPLAY INVISIBLE (-2975 -1175);
FORCEPROP 1 LAST COMMENT_BODY TRUE
J 0
(-3175 -1150);
DISPLAY 0.872340 (-3175 -1150);
PAINT GREEN (-3175 -1150);
DISPLAY INVISIBLE (-3175 -1150);
FORCEPROP 2 LAST CDS_LIB standard
J 0
(-3300 -1050);
DISPLAY INVISIBLE (-3300 -1050);
FORCEPROP 2 LAST PATH I2
J 0
(-3550 -1000);
DISPLAY 1.021277 (-3550 -1000);
DISPLAY INVISIBLE (-3550 -1000);
FORCEADD OFFPAGE..2
R 2
(-3300 250);
FORCEPROP 2 LAST $XR0 61 
J 0
(-3554 250);
DISPLAY 0.638298 (-3554 250);
PAINT MONO (-3554 250);
FORCEPROP 1 LAST OFFPAGE TRUE
J 2
(-3625 125);
DISPLAY 0.872340 (-3625 125);
PAINT AQUA (-3625 125);
DISPLAY INVISIBLE (-3625 125);
FORCEPROP 1 LAST COMMENT_BODY TRUE
J 2
(-3255 155);
DISPLAY 0.872340 (-3255 155);
PAINT GREEN (-3255 155);
DISPLAY INVISIBLE (-3255 155);
FORCEPROP 2 LAST CDS_LIB standard
J 0
(-3300 250);
DISPLAY INVISIBLE (-3300 250);
FORCEPROP 2 LAST PATH I20
J 0
(-3550 300);
DISPLAY 1.021277 (-3550 300);
DISPLAY INVISIBLE (-3550 300);
FORCEADD OFFPAGE..1
(-3300 500);
FORCEPROP 2 LAST $XR0 176 
J 0
(-3552 500);
DISPLAY 0.638298 (-3552 500);
PAINT MONO (-3552 500);
FORCEPROP 2 LAST CDS_LIB standard
J 0
(-3300 500);
DISPLAY INVISIBLE (-3300 500);
FORCEPROP 1 LAST COMMENT_BODY TRUE
J 0
(-3175 400);
DISPLAY 0.872340 (-3175 400);
PAINT GREEN (-3175 400);
DISPLAY INVISIBLE (-3175 400);
FORCEPROP 1 LAST OFFPAGE TRUE
J 0
(-2975 375);
DISPLAY 0.872340 (-2975 375);
PAINT AQUA (-2975 375);
DISPLAY INVISIBLE (-2975 375);
FORCEPROP 2 LAST PATH I21
J 0
(-3550 550);
DISPLAY 1.021277 (-3550 550);
DISPLAY INVISIBLE (-3550 550);
FORCEADD OFFPAGE..1
(-3300 550);
FORCEPROP 2 LAST $XR0 176 
J 0
(-3552 550);
DISPLAY 0.638298 (-3552 550);
PAINT MONO (-3552 550);
FORCEPROP 1 LAST OFFPAGE TRUE
J 0
(-2975 425);
DISPLAY 0.872340 (-2975 425);
PAINT AQUA (-2975 425);
DISPLAY INVISIBLE (-2975 425);
FORCEPROP 1 LAST COMMENT_BODY TRUE
J 0
(-3175 450);
DISPLAY 0.872340 (-3175 450);
PAINT GREEN (-3175 450);
DISPLAY INVISIBLE (-3175 450);
FORCEPROP 2 LAST CDS_LIB standard
J 0
(-3300 550);
DISPLAY INVISIBLE (-3300 550);
FORCEPROP 2 LAST PATH I22
J 0
(-3550 600);
DISPLAY 1.021277 (-3550 600);
DISPLAY INVISIBLE (-3550 600);
FORCEADD OFFPAGE..1
(-3300 650);
FORCEPROP 2 LAST $XR0 177 
J 0
(-3552 650);
DISPLAY 0.638298 (-3552 650);
PAINT MONO (-3552 650);
FORCEPROP 2 LAST CDS_LIB standard
J 0
(-3300 650);
DISPLAY INVISIBLE (-3300 650);
FORCEPROP 1 LAST COMMENT_BODY TRUE
J 0
(-3175 550);
DISPLAY 0.872340 (-3175 550);
PAINT GREEN (-3175 550);
DISPLAY INVISIBLE (-3175 550);
FORCEPROP 1 LAST OFFPAGE TRUE
J 0
(-2975 525);
DISPLAY 0.872340 (-2975 525);
PAINT AQUA (-2975 525);
DISPLAY INVISIBLE (-2975 525);
FORCEPROP 2 LAST PATH I23
J 0
(-3550 700);
DISPLAY 1.021277 (-3550 700);
DISPLAY INVISIBLE (-3550 700);
FORCEADD OFFPAGE..1
(-3300 700);
FORCEPROP 2 LAST $XR0 177 
J 0
(-3552 700);
DISPLAY 0.638298 (-3552 700);
PAINT MONO (-3552 700);
FORCEPROP 1 LAST OFFPAGE TRUE
J 0
(-2975 575);
DISPLAY 0.872340 (-2975 575);
PAINT AQUA (-2975 575);
DISPLAY INVISIBLE (-2975 575);
FORCEPROP 1 LAST COMMENT_BODY TRUE
J 0
(-3175 600);
DISPLAY 0.872340 (-3175 600);
PAINT GREEN (-3175 600);
DISPLAY INVISIBLE (-3175 600);
FORCEPROP 2 LAST CDS_LIB standard
J 0
(-3300 700);
DISPLAY INVISIBLE (-3300 700);
FORCEPROP 2 LAST PATH I24
J 0
(-3550 750);
DISPLAY 1.021277 (-3550 750);
DISPLAY INVISIBLE (-3550 750);
FORCEADD OFFPAGE..5
(-3300 800);
FORCEPROP 2 LAST $XR0 61 
J 0
(-3554 800);
DISPLAY 0.638298 (-3554 800);
PAINT MONO (-3554 800);
FORCEPROP 2 LAST CDS_LIB standard
J 0
(-3300 800);
DISPLAY INVISIBLE (-3300 800);
FORCEPROP 1 LAST COMMENT_BODY TRUE
J 0
(-3200 725);
DISPLAY 1.170213 (-3200 725);
PAINT GREEN (-3200 725);
DISPLAY INVISIBLE (-3200 725);
FORCEPROP 1 LAST OFFPAGE TRUE
J 0
(-2975 675);
DISPLAY 0.872340 (-2975 675);
PAINT AQUA (-2975 675);
DISPLAY INVISIBLE (-2975 675);
FORCEPROP 2 LAST PATH I25
J 0
(-3550 850);
DISPLAY 1.021277 (-3550 850);
DISPLAY INVISIBLE (-3550 850);
FORCEADD OFFPAGE..2
R 2
(-3300 850);
FORCEPROP 2 LAST $XR0 61 
J 0
(-3554 850);
DISPLAY 0.638298 (-3554 850);
PAINT MONO (-3554 850);
FORCEPROP 2 LAST CDS_LIB standard
J 0
(-3300 850);
DISPLAY INVISIBLE (-3300 850);
FORCEPROP 1 LAST COMMENT_BODY TRUE
J 2
(-3255 755);
DISPLAY 0.872340 (-3255 755);
PAINT GREEN (-3255 755);
DISPLAY INVISIBLE (-3255 755);
FORCEPROP 1 LAST OFFPAGE TRUE
J 2
(-3625 725);
DISPLAY 0.872340 (-3625 725);
PAINT AQUA (-3625 725);
DISPLAY INVISIBLE (-3625 725);
FORCEPROP 2 LAST PATH I26
J 0
(-3550 900);
DISPLAY 1.021277 (-3550 900);
DISPLAY INVISIBLE (-3550 900);
FORCEADD OFFPAGE..5
(-3300 950);
FORCEPROP 2 LAST $XR0 61 
J 0
(-3554 950);
DISPLAY 0.638298 (-3554 950);
PAINT MONO (-3554 950);
FORCEPROP 2 LAST CDS_LIB standard
J 0
(-3300 950);
DISPLAY INVISIBLE (-3300 950);
FORCEPROP 1 LAST COMMENT_BODY TRUE
J 0
(-3200 875);
DISPLAY 1.170213 (-3200 875);
PAINT GREEN (-3200 875);
DISPLAY INVISIBLE (-3200 875);
FORCEPROP 1 LAST OFFPAGE TRUE
J 0
(-2975 825);
DISPLAY 0.872340 (-2975 825);
PAINT AQUA (-2975 825);
DISPLAY INVISIBLE (-2975 825);
FORCEPROP 2 LAST PATH I27
J 0
(-3550 1000);
DISPLAY 1.021277 (-3550 1000);
DISPLAY INVISIBLE (-3550 1000);
FORCEADD OFFPAGE..2
R 2
(-3300 1000);
FORCEPROP 2 LAST $XR0 61 
J 0
(-3554 1000);
DISPLAY 0.638298 (-3554 1000);
PAINT MONO (-3554 1000);
FORCEPROP 2 LAST CDS_LIB standard
J 0
(-3300 1000);
DISPLAY INVISIBLE (-3300 1000);
FORCEPROP 1 LAST COMMENT_BODY TRUE
J 2
(-3255 905);
DISPLAY 0.872340 (-3255 905);
PAINT GREEN (-3255 905);
DISPLAY INVISIBLE (-3255 905);
FORCEPROP 1 LAST OFFPAGE TRUE
J 2
(-3625 875);
DISPLAY 0.872340 (-3625 875);
PAINT AQUA (-3625 875);
DISPLAY INVISIBLE (-3625 875);
FORCEPROP 2 LAST PATH I28
J 0
(-3550 1050);
DISPLAY 1.021277 (-3550 1050);
DISPLAY INVISIBLE (-3550 1050);
FORCEADD OFFPAGE..5
(-3300 -800);
FORCEPROP 2 LAST $XR0 61 
J 0
(-3554 -800);
DISPLAY 0.638298 (-3554 -800);
PAINT MONO (-3554 -800);
FORCEPROP 2 LAST CDS_LIB standard
J 0
(-3300 -800);
DISPLAY INVISIBLE (-3300 -800);
FORCEPROP 1 LAST COMMENT_BODY TRUE
J 0
(-3200 -875);
DISPLAY 1.170213 (-3200 -875);
PAINT GREEN (-3200 -875);
DISPLAY INVISIBLE (-3200 -875);
FORCEPROP 1 LAST OFFPAGE TRUE
J 0
(-2975 -925);
DISPLAY 0.872340 (-2975 -925);
PAINT AQUA (-2975 -925);
DISPLAY INVISIBLE (-2975 -925);
FORCEPROP 2 LAST PATH I3
J 0
(-3550 -750);
DISPLAY 1.021277 (-3550 -750);
DISPLAY INVISIBLE (-3550 -750);
FORCEADD OFFPAGE..1
(-3300 1350);
FORCEPROP 2 LAST $XR0 176 
J 0
(-3552 1350);
DISPLAY 0.638298 (-3552 1350);
PAINT MONO (-3552 1350);
FORCEPROP 1 LAST COMMENT_BODY TRUE
J 0
(-3175 1250);
DISPLAY 0.872340 (-3175 1250);
PAINT GREEN (-3175 1250);
DISPLAY INVISIBLE (-3175 1250);
FORCEPROP 1 LAST OFFPAGE TRUE
J 0
(-2975 1225);
DISPLAY 0.872340 (-2975 1225);
PAINT AQUA (-2975 1225);
DISPLAY INVISIBLE (-2975 1225);
FORCEPROP 2 LAST PATH I31
J 0
(-3550 1400);
DISPLAY 1.021277 (-3550 1400);
DISPLAY INVISIBLE (-3550 1400);
FORCEPROP 2 LAST CDS_LIB standard
J 0
(-3300 1350);
DISPLAY INVISIBLE (-3300 1350);
FORCEADD OFFPAGE..1
(-3300 1400);
FORCEPROP 2 LAST $XR0 176 
J 0
(-3552 1400);
DISPLAY 0.638298 (-3552 1400);
PAINT MONO (-3552 1400);
FORCEPROP 1 LAST OFFPAGE TRUE
J 0
(-2975 1275);
DISPLAY 0.872340 (-2975 1275);
PAINT AQUA (-2975 1275);
DISPLAY INVISIBLE (-2975 1275);
FORCEPROP 1 LAST COMMENT_BODY TRUE
J 0
(-3175 1300);
DISPLAY 0.872340 (-3175 1300);
PAINT GREEN (-3175 1300);
DISPLAY INVISIBLE (-3175 1300);
FORCEPROP 2 LAST CDS_LIB standard
J 0
(-3300 1400);
DISPLAY INVISIBLE (-3300 1400);
FORCEPROP 2 LAST PATH I32
J 0
(-3550 1450);
DISPLAY 1.021277 (-3550 1450);
DISPLAY INVISIBLE (-3550 1450);
FORCEADD OFFPAGE..1
(-3300 1500);
FORCEPROP 2 LAST $XR0 177 
J 0
(-3552 1500);
DISPLAY 0.638298 (-3552 1500);
PAINT MONO (-3552 1500);
FORCEPROP 2 LAST CDS_LIB standard
J 0
(-3300 1500);
DISPLAY INVISIBLE (-3300 1500);
FORCEPROP 1 LAST COMMENT_BODY TRUE
J 0
(-3175 1400);
DISPLAY 0.872340 (-3175 1400);
PAINT GREEN (-3175 1400);
DISPLAY INVISIBLE (-3175 1400);
FORCEPROP 1 LAST OFFPAGE TRUE
J 0
(-2975 1375);
DISPLAY 0.872340 (-2975 1375);
PAINT AQUA (-2975 1375);
DISPLAY INVISIBLE (-2975 1375);
FORCEPROP 2 LAST PATH I33
J 0
(-3550 1550);
DISPLAY 1.021277 (-3550 1550);
DISPLAY INVISIBLE (-3550 1550);
FORCEADD OFFPAGE..1
(-3300 1550);
FORCEPROP 2 LAST $XR0 177 
J 0
(-3552 1550);
DISPLAY 0.638298 (-3552 1550);
PAINT MONO (-3552 1550);
FORCEPROP 1 LAST OFFPAGE TRUE
J 0
(-2975 1425);
DISPLAY 0.872340 (-2975 1425);
PAINT AQUA (-2975 1425);
DISPLAY INVISIBLE (-2975 1425);
FORCEPROP 1 LAST COMMENT_BODY TRUE
J 0
(-3175 1450);
DISPLAY 0.872340 (-3175 1450);
PAINT GREEN (-3175 1450);
DISPLAY INVISIBLE (-3175 1450);
FORCEPROP 2 LAST CDS_LIB standard
J 0
(-3300 1550);
DISPLAY INVISIBLE (-3300 1550);
FORCEPROP 2 LAST PATH I34
J 0
(-3550 1600);
DISPLAY 1.021277 (-3550 1600);
DISPLAY INVISIBLE (-3550 1600);
FORCEADD OFFPAGE..5
(-3300 1650);
FORCEPROP 2 LAST $XR0 61 
J 0
(-3554 1650);
DISPLAY 0.638298 (-3554 1650);
PAINT MONO (-3554 1650);
FORCEPROP 1 LAST OFFPAGE TRUE
J 0
(-2975 1525);
DISPLAY 0.872340 (-2975 1525);
PAINT AQUA (-2975 1525);
DISPLAY INVISIBLE (-2975 1525);
FORCEPROP 1 LAST COMMENT_BODY TRUE
J 0
(-3200 1575);
DISPLAY 1.170213 (-3200 1575);
PAINT GREEN (-3200 1575);
DISPLAY INVISIBLE (-3200 1575);
FORCEPROP 2 LAST CDS_LIB standard
J 0
(-3300 1650);
DISPLAY INVISIBLE (-3300 1650);
FORCEPROP 2 LAST PATH I35
J 0
(-3550 1700);
DISPLAY 1.021277 (-3550 1700);
DISPLAY INVISIBLE (-3550 1700);
FORCEADD OFFPAGE..2
R 2
(-3300 1700);
FORCEPROP 2 LAST $XR0 61 
J 0
(-3554 1700);
DISPLAY 0.638298 (-3554 1700);
PAINT MONO (-3554 1700);
FORCEPROP 1 LAST OFFPAGE TRUE
J 2
(-3625 1575);
DISPLAY 0.872340 (-3625 1575);
PAINT AQUA (-3625 1575);
DISPLAY INVISIBLE (-3625 1575);
FORCEPROP 1 LAST COMMENT_BODY TRUE
J 2
(-3255 1605);
DISPLAY 0.872340 (-3255 1605);
PAINT GREEN (-3255 1605);
DISPLAY INVISIBLE (-3255 1605);
FORCEPROP 2 LAST CDS_LIB standard
J 0
(-3300 1700);
DISPLAY INVISIBLE (-3300 1700);
FORCEPROP 2 LAST PATH I36
J 0
(-3550 1750);
DISPLAY 1.021277 (-3550 1750);
DISPLAY INVISIBLE (-3550 1750);
FORCEADD OFFPAGE..2
R 2
(-3300 1850);
FORCEPROP 2 LAST $XR0 61 
J 0
(-3554 1850);
DISPLAY 0.638298 (-3554 1850);
PAINT MONO (-3554 1850);
FORCEPROP 2 LAST CDS_LIB standard
J 0
(-3300 1850);
DISPLAY INVISIBLE (-3300 1850);
FORCEPROP 1 LAST COMMENT_BODY TRUE
J 2
(-3255 1755);
DISPLAY 0.872340 (-3255 1755);
PAINT GREEN (-3255 1755);
DISPLAY INVISIBLE (-3255 1755);
FORCEPROP 1 LAST OFFPAGE TRUE
J 2
(-3625 1725);
DISPLAY 0.872340 (-3625 1725);
PAINT AQUA (-3625 1725);
DISPLAY INVISIBLE (-3625 1725);
FORCEPROP 2 LAST PATH I37
J 0
(-3550 1900);
DISPLAY 1.021277 (-3550 1900);
DISPLAY INVISIBLE (-3550 1900);
FORCEADD OFFPAGE..5
(-3300 1800);
FORCEPROP 2 LAST $XR0 61 
J 0
(-3554 1800);
DISPLAY 0.638298 (-3554 1800);
PAINT MONO (-3554 1800);
FORCEPROP 2 LAST CDS_LIB standard
J 0
(-3300 1800);
DISPLAY INVISIBLE (-3300 1800);
FORCEPROP 1 LAST COMMENT_BODY TRUE
J 0
(-3200 1725);
DISPLAY 1.170213 (-3200 1725);
PAINT GREEN (-3200 1725);
DISPLAY INVISIBLE (-3200 1725);
FORCEPROP 1 LAST OFFPAGE TRUE
J 0
(-2975 1675);
DISPLAY 0.872340 (-2975 1675);
PAINT AQUA (-2975 1675);
DISPLAY INVISIBLE (-2975 1675);
FORCEPROP 2 LAST PATH I38
J 0
(-3550 1850);
DISPLAY 1.021277 (-3550 1850);
DISPLAY INVISIBLE (-3550 1850);
FORCEADD OFFPAGE..1
(1450 -1000);
FORCEPROP 2 LAST $XR0 176 
J 0
(1198 -1000);
DISPLAY 0.638298 (1198 -1000);
PAINT MONO (1198 -1000);
FORCEPROP 2 LAST PATH I39
J 0
(1200 -950);
DISPLAY 1.021277 (1200 -950);
DISPLAY INVISIBLE (1200 -950);
FORCEPROP 2 LAST CDS_LIB standard
J 0
(1450 -1000);
DISPLAY INVISIBLE (1450 -1000);
FORCEPROP 1 LAST COMMENT_BODY TRUE
J 0
(1575 -1100);
DISPLAY 0.872340 (1575 -1100);
PAINT GREEN (1575 -1100);
DISPLAY INVISIBLE (1575 -1100);
FORCEPROP 1 LAST OFFPAGE TRUE
J 0
(1775 -1125);
DISPLAY 0.872340 (1775 -1125);
PAINT AQUA (1775 -1125);
DISPLAY INVISIBLE (1775 -1125);
FORCEADD OFFPAGE..1
(-3300 -950);
FORCEPROP 2 LAST $XR0 177 
J 0
(-3552 -950);
DISPLAY 0.638298 (-3552 -950);
PAINT MONO (-3552 -950);
FORCEPROP 1 LAST OFFPAGE TRUE
J 0
(-2975 -1075);
DISPLAY 0.872340 (-2975 -1075);
PAINT AQUA (-2975 -1075);
DISPLAY INVISIBLE (-2975 -1075);
FORCEPROP 1 LAST COMMENT_BODY TRUE
J 0
(-3175 -1050);
DISPLAY 0.872340 (-3175 -1050);
PAINT GREEN (-3175 -1050);
DISPLAY INVISIBLE (-3175 -1050);
FORCEPROP 2 LAST CDS_LIB standard
J 0
(-3300 -950);
DISPLAY INVISIBLE (-3300 -950);
FORCEPROP 2 LAST PATH I4
J 0
(-3550 -900);
DISPLAY 1.021277 (-3550 -900);
DISPLAY INVISIBLE (-3550 -900);
FORCEADD OFFPAGE..1
(1450 -1050);
FORCEPROP 2 LAST $XR0 176 
J 0
(1198 -1050);
DISPLAY 0.638298 (1198 -1050);
PAINT MONO (1198 -1050);
FORCEPROP 2 LAST PATH I40
J 0
(1200 -1000);
DISPLAY 1.021277 (1200 -1000);
DISPLAY INVISIBLE (1200 -1000);
FORCEPROP 2 LAST CDS_LIB standard
J 0
(1450 -1050);
DISPLAY INVISIBLE (1450 -1050);
FORCEPROP 1 LAST COMMENT_BODY TRUE
J 0
(1575 -1150);
DISPLAY 0.872340 (1575 -1150);
PAINT GREEN (1575 -1150);
DISPLAY INVISIBLE (1575 -1150);
FORCEPROP 1 LAST OFFPAGE TRUE
J 0
(1775 -1175);
DISPLAY 0.872340 (1775 -1175);
PAINT AQUA (1775 -1175);
DISPLAY INVISIBLE (1775 -1175);
FORCEADD OFFPAGE..5
(1450 -750);
FORCEPROP 2 LAST $XR0 61 
J 0
(1196 -750);
DISPLAY 0.638298 (1196 -750);
PAINT MONO (1196 -750);
FORCEPROP 2 LAST PATH I41
J 0
(1200 -700);
DISPLAY 1.021277 (1200 -700);
DISPLAY INVISIBLE (1200 -700);
FORCEPROP 2 LAST CDS_LIB standard
J 0
(1450 -750);
DISPLAY INVISIBLE (1450 -750);
FORCEPROP 1 LAST COMMENT_BODY TRUE
J 0
(1550 -825);
DISPLAY 1.170213 (1550 -825);
PAINT GREEN (1550 -825);
DISPLAY INVISIBLE (1550 -825);
FORCEPROP 1 LAST OFFPAGE TRUE
J 0
(1775 -875);
DISPLAY 0.872340 (1775 -875);
PAINT AQUA (1775 -875);
DISPLAY INVISIBLE (1775 -875);
FORCEADD OFFPAGE..1
(1450 -900);
FORCEPROP 2 LAST $XR0 177 
J 0
(1198 -900);
DISPLAY 0.638298 (1198 -900);
PAINT MONO (1198 -900);
FORCEPROP 2 LAST PATH I42
J 0
(1200 -850);
DISPLAY 1.021277 (1200 -850);
DISPLAY INVISIBLE (1200 -850);
FORCEPROP 1 LAST OFFPAGE TRUE
J 0
(1775 -1025);
DISPLAY 0.872340 (1775 -1025);
PAINT AQUA (1775 -1025);
DISPLAY INVISIBLE (1775 -1025);
FORCEPROP 1 LAST COMMENT_BODY TRUE
J 0
(1575 -1000);
DISPLAY 0.872340 (1575 -1000);
PAINT GREEN (1575 -1000);
DISPLAY INVISIBLE (1575 -1000);
FORCEPROP 2 LAST CDS_LIB standard
J 0
(1450 -900);
DISPLAY INVISIBLE (1450 -900);
FORCEADD OFFPAGE..1
(1450 -850);
FORCEPROP 2 LAST $XR0 177 
J 0
(1198 -850);
DISPLAY 0.638298 (1198 -850);
PAINT MONO (1198 -850);
FORCEPROP 2 LAST PATH I43
J 0
(1200 -800);
DISPLAY 1.021277 (1200 -800);
DISPLAY INVISIBLE (1200 -800);
FORCEPROP 1 LAST OFFPAGE TRUE
J 0
(1775 -975);
DISPLAY 0.872340 (1775 -975);
PAINT AQUA (1775 -975);
DISPLAY INVISIBLE (1775 -975);
FORCEPROP 1 LAST COMMENT_BODY TRUE
J 0
(1575 -950);
DISPLAY 0.872340 (1575 -950);
PAINT GREEN (1575 -950);
DISPLAY INVISIBLE (1575 -950);
FORCEPROP 2 LAST CDS_LIB standard
J 0
(1450 -850);
DISPLAY INVISIBLE (1450 -850);
FORCEADD OFFPAGE..2
R 2
(1450 -700);
FORCEPROP 2 LAST $XR0 61 
J 0
(1196 -700);
DISPLAY 0.638298 (1196 -700);
PAINT MONO (1196 -700);
FORCEPROP 2 LAST PATH I44
J 0
(1200 -650);
DISPLAY 1.021277 (1200 -650);
DISPLAY INVISIBLE (1200 -650);
FORCEPROP 2 LAST CDS_LIB standard
J 0
(1450 -700);
DISPLAY INVISIBLE (1450 -700);
FORCEPROP 1 LAST COMMENT_BODY TRUE
J 2
(1495 -795);
DISPLAY 0.872340 (1495 -795);
PAINT GREEN (1495 -795);
DISPLAY INVISIBLE (1495 -795);
FORCEPROP 1 LAST OFFPAGE TRUE
J 2
(1125 -825);
DISPLAY 0.872340 (1125 -825);
PAINT AQUA (1125 -825);
DISPLAY INVISIBLE (1125 -825);
FORCEADD OFFPAGE..5
(1450 -600);
FORCEPROP 2 LAST $XR0 61 
J 0
(1196 -600);
DISPLAY 0.638298 (1196 -600);
PAINT MONO (1196 -600);
FORCEPROP 2 LAST PATH I45
J 0
(1200 -550);
DISPLAY 1.021277 (1200 -550);
DISPLAY INVISIBLE (1200 -550);
FORCEPROP 2 LAST CDS_LIB standard
J 0
(1450 -600);
DISPLAY INVISIBLE (1450 -600);
FORCEPROP 1 LAST COMMENT_BODY TRUE
J 0
(1550 -675);
DISPLAY 1.170213 (1550 -675);
PAINT GREEN (1550 -675);
DISPLAY INVISIBLE (1550 -675);
FORCEPROP 1 LAST OFFPAGE TRUE
J 0
(1775 -725);
DISPLAY 0.872340 (1775 -725);
PAINT AQUA (1775 -725);
DISPLAY INVISIBLE (1775 -725);
FORCEADD OFFPAGE..2
R 2
(1450 -550);
FORCEPROP 2 LAST $XR0 61 
J 0
(1196 -550);
DISPLAY 0.638298 (1196 -550);
PAINT MONO (1196 -550);
FORCEPROP 2 LAST PATH I46
J 0
(1200 -500);
DISPLAY 1.021277 (1200 -500);
DISPLAY INVISIBLE (1200 -500);
FORCEPROP 2 LAST CDS_LIB standard
J 0
(1450 -550);
DISPLAY INVISIBLE (1450 -550);
FORCEPROP 1 LAST COMMENT_BODY TRUE
J 2
(1495 -645);
DISPLAY 0.872340 (1495 -645);
PAINT GREEN (1495 -645);
DISPLAY INVISIBLE (1495 -645);
FORCEPROP 1 LAST OFFPAGE TRUE
J 2
(1125 -675);
DISPLAY 0.872340 (1125 -675);
PAINT AQUA (1125 -675);
DISPLAY INVISIBLE (1125 -675);
FORCEADD OFFPAGE..1
(1450 -200);
FORCEPROP 2 LAST $XR0 176 
J 0
(1198 -200);
DISPLAY 0.638298 (1198 -200);
PAINT MONO (1198 -200);
FORCEPROP 2 LAST PATH I49
J 0
(1200 -150);
DISPLAY 1.021277 (1200 -150);
DISPLAY INVISIBLE (1200 -150);
FORCEPROP 2 LAST CDS_LIB standard
J 0
(1450 -200);
DISPLAY INVISIBLE (1450 -200);
FORCEPROP 1 LAST COMMENT_BODY TRUE
J 0
(1575 -300);
DISPLAY 0.872340 (1575 -300);
PAINT GREEN (1575 -300);
DISPLAY INVISIBLE (1575 -300);
FORCEPROP 1 LAST OFFPAGE TRUE
J 0
(1775 -325);
DISPLAY 0.872340 (1775 -325);
PAINT AQUA (1775 -325);
DISPLAY INVISIBLE (1775 -325);
FORCEADD OFFPAGE..1
(-3300 -900);
FORCEPROP 2 LAST $XR0 177 
J 0
(-3552 -900);
DISPLAY 0.638298 (-3552 -900);
PAINT MONO (-3552 -900);
FORCEPROP 1 LAST OFFPAGE TRUE
J 0
(-2975 -1025);
DISPLAY 0.872340 (-2975 -1025);
PAINT AQUA (-2975 -1025);
DISPLAY INVISIBLE (-2975 -1025);
FORCEPROP 1 LAST COMMENT_BODY TRUE
J 0
(-3175 -1000);
DISPLAY 0.872340 (-3175 -1000);
PAINT GREEN (-3175 -1000);
DISPLAY INVISIBLE (-3175 -1000);
FORCEPROP 2 LAST CDS_LIB standard
J 0
(-3300 -900);
DISPLAY INVISIBLE (-3300 -900);
FORCEPROP 2 LAST PATH I5
J 0
(-3550 -850);
DISPLAY 1.021277 (-3550 -850);
DISPLAY INVISIBLE (-3550 -850);
FORCEADD OFFPAGE..1
(1450 0);
FORCEPROP 2 LAST $XR0 177 
J 0
(1198 0);
DISPLAY 0.638298 (1198 0);
PAINT MONO (1198 0);
FORCEPROP 2 LAST PATH I50
J 0
(1200 50);
DISPLAY 1.021277 (1200 50);
DISPLAY INVISIBLE (1200 50);
FORCEPROP 1 LAST OFFPAGE TRUE
J 0
(1775 -125);
DISPLAY 0.872340 (1775 -125);
PAINT AQUA (1775 -125);
DISPLAY INVISIBLE (1775 -125);
FORCEPROP 1 LAST COMMENT_BODY TRUE
J 0
(1575 -100);
DISPLAY 0.872340 (1575 -100);
PAINT GREEN (1575 -100);
DISPLAY INVISIBLE (1575 -100);
FORCEPROP 2 LAST CDS_LIB standard
J 0
(1450 0);
DISPLAY INVISIBLE (1450 0);
FORCEADD OFFPAGE..1
(1450 -50);
FORCEPROP 2 LAST $XR0 177 
J 0
(1198 -50);
DISPLAY 0.638298 (1198 -50);
PAINT MONO (1198 -50);
FORCEPROP 2 LAST PATH I51
J 0
(1200 0);
DISPLAY 1.021277 (1200 0);
DISPLAY INVISIBLE (1200 0);
FORCEPROP 1 LAST OFFPAGE TRUE
J 0
(1775 -175);
DISPLAY 0.872340 (1775 -175);
PAINT AQUA (1775 -175);
DISPLAY INVISIBLE (1775 -175);
FORCEPROP 1 LAST COMMENT_BODY TRUE
J 0
(1575 -150);
DISPLAY 0.872340 (1575 -150);
PAINT GREEN (1575 -150);
DISPLAY INVISIBLE (1575 -150);
FORCEPROP 2 LAST CDS_LIB standard
J 0
(1450 -50);
DISPLAY INVISIBLE (1450 -50);
FORCEADD OFFPAGE..1
(1450 -150);
FORCEPROP 2 LAST $XR0 176 
J 0
(1198 -150);
DISPLAY 0.638298 (1198 -150);
PAINT MONO (1198 -150);
FORCEPROP 2 LAST PATH I52
J 0
(1200 -100);
DISPLAY 1.021277 (1200 -100);
DISPLAY INVISIBLE (1200 -100);
FORCEPROP 2 LAST CDS_LIB standard
J 0
(1450 -150);
DISPLAY INVISIBLE (1450 -150);
FORCEPROP 1 LAST COMMENT_BODY TRUE
J 0
(1575 -250);
DISPLAY 0.872340 (1575 -250);
PAINT GREEN (1575 -250);
DISPLAY INVISIBLE (1575 -250);
FORCEPROP 1 LAST OFFPAGE TRUE
J 0
(1775 -275);
DISPLAY 0.872340 (1775 -275);
PAINT AQUA (1775 -275);
DISPLAY INVISIBLE (1775 -275);
FORCEADD UNIVERSAL_GND..1
(2525 -1500);
FORCEPROP 3 LASTPIN (2525 -1450) SIG_NAME GND\g
J 0
(2535 -1440);
DISPLAY 0.659574 (2535 -1440);
PAINT MONO (2535 -1440);
DISPLAY INVISIBLE (2535 -1440);
FORCEPROP 1 LAST PATH I53
J 0
(2600 -1500);
DISPLAY 0.872340 (2600 -1500);
PAINT AQUA (2600 -1500);
DISPLAY INVISIBLE (2600 -1500);
FORCEPROP 1 LAST HDL_POWER GND
J 1
(2550 -1575);
DISPLAY 0.872340 (2550 -1575);
PAINT GREEN (2550 -1575);
DISPLAY INVISIBLE (2550 -1575);
FORCEPROP 2 LAST CDS_LIB logical_power
J 0
(2525 -1500);
DISPLAY INVISIBLE (2525 -1500);
FORCEADD CONN112_10137002101LF..2
(3675 450);
FORCEPROP 1 LAST PART_NUMBER DFHSB2FR012
J 0
(2925 2225);
DISPLAY 0.723404 (2925 2225);
PAINT GREEN (2925 2225);
DISPLAY INVISIBLE (2925 2225);
FORCEPROP 2 LAST PART_TYPE THLF
J 0
(2925 2350);
DISPLAY 1.021277 (2925 2350);
FORCEPROP 1 LAST MATERIAL IO
J 0
(2933 2163);
DISPLAY 0.723404 (2933 2163);
PAINT GREEN (2933 2163);
FORCEPROP 1 LAST LOCATION J110
J 0
(2925 2275);
DISPLAY 0.723404 (2925 2275);
PAINT GREEN (2925 2275);
FORCEPROP 0 LASTPIN (2750 -450) $PN A1
J 2
(2740 -440);
DISPLAY 0.680851 (2740 -440);
PAINT MONO (2740 -440);
FORCEPROP 0 LASTPIN (2750 350) $PN A2
J 2
(2740 360);
DISPLAY 0.680851 (2740 360);
PAINT MONO (2740 360);
FORCEPROP 0 LASTPIN (2750 1150) $PN A3
J 2
(2740 1160);
DISPLAY 0.680851 (2740 1160);
PAINT MONO (2740 1160);
FORCEPROP 0 LASTPIN (2750 1950) $PN A4
J 2
(2740 1960);
DISPLAY 0.680851 (2740 1960);
PAINT MONO (2740 1960);
FORCEPROP 0 LASTPIN (2750 -500) $PN B1
J 2
(2740 -490);
DISPLAY 0.680851 (2740 -490);
PAINT MONO (2740 -490);
FORCEPROP 0 LASTPIN (2750 300) $PN B2
J 2
(2740 310);
DISPLAY 0.680851 (2740 310);
PAINT MONO (2740 310);
FORCEPROP 0 LASTPIN (2750 1100) $PN B3
J 2
(2740 1110);
DISPLAY 0.680851 (2740 1110);
PAINT MONO (2740 1110);
FORCEPROP 0 LASTPIN (2750 1900) $PN B4
J 2
(2740 1910);
DISPLAY 0.680851 (2740 1910);
PAINT MONO (2740 1910);
FORCEPROP 0 LASTPIN (2750 -550) $PN C1
J 2
(2740 -540);
DISPLAY 0.680851 (2740 -540);
PAINT MONO (2740 -540);
FORCEPROP 0 LASTPIN (2750 250) $PN C2
J 2
(2740 260);
DISPLAY 0.680851 (2740 260);
PAINT MONO (2740 260);
FORCEPROP 0 LASTPIN (2750 1050) $PN C3
J 2
(2740 1060);
DISPLAY 0.680851 (2740 1060);
PAINT MONO (2740 1060);
FORCEPROP 0 LASTPIN (2750 1850) $PN C4
J 2
(2740 1860);
DISPLAY 0.680851 (2740 1860);
PAINT MONO (2740 1860);
FORCEPROP 0 LASTPIN (2750 -600) $PN D1
J 2
(2740 -590);
DISPLAY 0.680851 (2740 -590);
PAINT MONO (2740 -590);
FORCEPROP 0 LASTPIN (2750 200) $PN D2
J 2
(2740 210);
DISPLAY 0.680851 (2740 210);
PAINT MONO (2740 210);
FORCEPROP 0 LASTPIN (2750 1000) $PN D3
J 2
(2740 1010);
DISPLAY 0.680851 (2740 1010);
PAINT MONO (2740 1010);
FORCEPROP 0 LASTPIN (2750 1800) $PN D4
J 2
(2740 1810);
DISPLAY 0.680851 (2740 1810);
PAINT MONO (2740 1810);
FORCEPROP 0 LASTPIN (2750 -650) $PN E1
J 2
(2740 -640);
DISPLAY 0.680851 (2740 -640);
PAINT MONO (2740 -640);
FORCEPROP 0 LASTPIN (2750 150) $PN E2
J 2
(2740 160);
DISPLAY 0.680851 (2740 160);
PAINT MONO (2740 160);
FORCEPROP 0 LASTPIN (2750 950) $PN E3
J 2
(2740 960);
DISPLAY 0.680851 (2740 960);
PAINT MONO (2740 960);
FORCEPROP 0 LASTPIN (2750 1750) $PN E4
J 2
(2740 1760);
DISPLAY 0.680851 (2740 1760);
PAINT MONO (2740 1760);
FORCEPROP 0 LASTPIN (2750 -700) $PN F1
J 2
(2740 -690);
DISPLAY 0.680851 (2740 -690);
PAINT MONO (2740 -690);
FORCEPROP 0 LASTPIN (2750 100) $PN F2
J 2
(2740 110);
DISPLAY 0.680851 (2740 110);
PAINT MONO (2740 110);
FORCEPROP 0 LASTPIN (2750 900) $PN F3
J 2
(2740 910);
DISPLAY 0.680851 (2740 910);
PAINT MONO (2740 910);
FORCEPROP 0 LASTPIN (2750 1700) $PN F4
J 2
(2740 1710);
DISPLAY 0.680851 (2740 1710);
PAINT MONO (2740 1710);
FORCEPROP 0 LASTPIN (2750 -750) $PN G1
J 2
(2740 -740);
DISPLAY 0.680851 (2740 -740);
PAINT MONO (2740 -740);
FORCEPROP 0 LASTPIN (2750 50) $PN G2
J 2
(2740 60);
DISPLAY 0.680851 (2740 60);
PAINT MONO (2740 60);
FORCEPROP 0 LASTPIN (2750 850) $PN G3
J 2
(2740 860);
DISPLAY 0.680851 (2740 860);
PAINT MONO (2740 860);
FORCEPROP 0 LASTPIN (2750 1650) $PN G4
J 2
(2740 1660);
DISPLAY 0.680851 (2740 1660);
PAINT MONO (2740 1660);
FORCEPROP 0 LASTPIN (2750 -800) $PN H1
J 2
(2740 -790);
DISPLAY 0.680851 (2740 -790);
PAINT MONO (2740 -790);
FORCEPROP 0 LASTPIN (2750 0) $PN H2
J 2
(2740 10);
DISPLAY 0.680851 (2740 10);
PAINT MONO (2740 10);
FORCEPROP 0 LASTPIN (2750 800) $PN H3
J 2
(2740 810);
DISPLAY 0.680851 (2740 810);
PAINT MONO (2740 810);
FORCEPROP 0 LASTPIN (2750 1600) $PN H4
J 2
(2740 1610);
DISPLAY 0.680851 (2740 1610);
PAINT MONO (2740 1610);
FORCEPROP 0 LASTPIN (2750 -850) $PN I1
J 2
(2740 -840);
DISPLAY 0.680851 (2740 -840);
PAINT MONO (2740 -840);
FORCEPROP 0 LASTPIN (2750 -50) $PN I2
J 2
(2740 -40);
DISPLAY 0.680851 (2740 -40);
PAINT MONO (2740 -40);
FORCEPROP 0 LASTPIN (2750 750) $PN I3
J 2
(2740 760);
DISPLAY 0.680851 (2740 760);
PAINT MONO (2740 760);
FORCEPROP 0 LASTPIN (2750 1550) $PN I4
J 2
(2740 1560);
DISPLAY 0.680851 (2740 1560);
PAINT MONO (2740 1560);
FORCEPROP 0 LASTPIN (2750 -900) $PN J1
J 2
(2740 -890);
DISPLAY 0.680851 (2740 -890);
PAINT MONO (2740 -890);
FORCEPROP 0 LASTPIN (2750 -100) $PN J2
J 2
(2740 -90);
DISPLAY 0.680851 (2740 -90);
PAINT MONO (2740 -90);
FORCEPROP 0 LASTPIN (2750 700) $PN J3
J 2
(2740 710);
DISPLAY 0.680851 (2740 710);
PAINT MONO (2740 710);
FORCEPROP 0 LASTPIN (2750 1500) $PN J4
J 2
(2740 1510);
DISPLAY 0.680851 (2740 1510);
PAINT MONO (2740 1510);
FORCEPROP 0 LASTPIN (2750 -950) $PN K1
J 2
(2740 -940);
DISPLAY 0.680851 (2740 -940);
PAINT MONO (2740 -940);
FORCEPROP 0 LASTPIN (2750 -150) $PN K2
J 2
(2740 -140);
DISPLAY 0.680851 (2740 -140);
PAINT MONO (2740 -140);
FORCEPROP 0 LASTPIN (2750 650) $PN K3
J 2
(2740 660);
DISPLAY 0.680851 (2740 660);
PAINT MONO (2740 660);
FORCEPROP 0 LASTPIN (2750 1450) $PN K4
J 2
(2740 1460);
DISPLAY 0.680851 (2740 1460);
PAINT MONO (2740 1460);
FORCEPROP 0 LASTPIN (2750 -1000) $PN L1
J 2
(2740 -990);
DISPLAY 0.680851 (2740 -990);
PAINT MONO (2740 -990);
FORCEPROP 0 LASTPIN (2750 -200) $PN L2
J 2
(2740 -190);
DISPLAY 0.680851 (2740 -190);
PAINT MONO (2740 -190);
FORCEPROP 0 LASTPIN (2750 600) $PN L3
J 2
(2740 610);
DISPLAY 0.680851 (2740 610);
PAINT MONO (2740 610);
FORCEPROP 0 LASTPIN (2750 1400) $PN L4
J 2
(2740 1410);
DISPLAY 0.680851 (2740 1410);
PAINT MONO (2740 1410);
FORCEPROP 0 LASTPIN (2750 -1050) $PN M1
J 2
(2740 -1040);
DISPLAY 0.680851 (2740 -1040);
PAINT MONO (2740 -1040);
FORCEPROP 0 LASTPIN (2750 -250) $PN M2
J 2
(2740 -240);
DISPLAY 0.680851 (2740 -240);
PAINT MONO (2740 -240);
FORCEPROP 0 LASTPIN (2750 550) $PN M3
J 2
(2740 560);
DISPLAY 0.680851 (2740 560);
PAINT MONO (2740 560);
FORCEPROP 0 LASTPIN (2750 1350) $PN M4
J 2
(2740 1360);
DISPLAY 0.680851 (2740 1360);
PAINT MONO (2740 1360);
FORCEPROP 0 LASTPIN (2750 -1100) $PN N1
J 2
(2740 -1090);
DISPLAY 0.680851 (2740 -1090);
PAINT MONO (2740 -1090);
FORCEPROP 0 LASTPIN (2750 -300) $PN N2
J 2
(2740 -290);
DISPLAY 0.680851 (2740 -290);
PAINT MONO (2740 -290);
FORCEPROP 0 LASTPIN (2750 500) $PN N3
J 2
(2740 510);
DISPLAY 0.680851 (2740 510);
PAINT MONO (2740 510);
FORCEPROP 0 LASTPIN (2750 1300) $PN N4
J 2
(2740 1310);
DISPLAY 0.680851 (2740 1310);
PAINT MONO (2740 1310);
FORCEPROP 1 LAST CDS_LMAN_SYM_OUTLINE -775,1650,775,-1650
J 0
(3675 450);
DISPLAY 0.468085 (3675 450);
PAINT GREEN (3675 450);
DISPLAY INVISIBLE (3675 450);
FORCEPROP 1 LAST NEEDS_NO_SIZE TRUE
J 0
(3675 450);
DISPLAY 0.723404 (3675 450);
PAINT GREEN (3675 450);
DISPLAY INVISIBLE (3675 450);
FORCEPROP 2 LAST CDS_LIB pure_quanta
J 0
(3675 450);
DISPLAY INVISIBLE (3675 450);
FORCEPROP 0 LAST VALUE CONN112_10137002-101LF
J 0
(2925 2350);
DISPLAY 1.021277 (2925 2350);
DISPLAY INVISIBLE (2925 2350);
FORCEPROP 1 LAST PATH I54
J 0
(3675 450);
DISPLAY 0.723404 (3675 450);
PAINT GREEN (3675 450);
DISPLAY INVISIBLE (3675 450);
FORCEPROP 0 LAST $SEC 2
J 0
(2925 2400);
DISPLAY 0.680851 (2925 2400);
PAINT MONO (2925 2400);
DISPLAY INVISIBLE (2925 2400);
FORCEPROP 0 LAST CDS_SEC 2
J 0
(2925 2400);
DISPLAY 1.021277 (2925 2400);
DISPLAY INVISIBLE (2925 2400);
FORCEADD OFFPAGE..5
(1450 100);
FORCEPROP 2 LAST $XR0 61 
J 0
(1196 100);
DISPLAY 0.638298 (1196 100);
PAINT MONO (1196 100);
FORCEPROP 2 LAST PATH I55
J 0
(1200 150);
DISPLAY 1.021277 (1200 150);
DISPLAY INVISIBLE (1200 150);
FORCEPROP 2 LAST CDS_LIB standard
J 0
(1450 100);
DISPLAY INVISIBLE (1450 100);
FORCEPROP 1 LAST COMMENT_BODY TRUE
J 0
(1550 25);
DISPLAY 1.170213 (1550 25);
PAINT GREEN (1550 25);
DISPLAY INVISIBLE (1550 25);
FORCEPROP 1 LAST OFFPAGE TRUE
J 0
(1775 -25);
DISPLAY 0.872340 (1775 -25);
PAINT AQUA (1775 -25);
DISPLAY INVISIBLE (1775 -25);
FORCEADD OFFPAGE..2
R 2
(1450 150);
FORCEPROP 2 LAST $XR0 61 
J 0
(1196 150);
DISPLAY 0.638298 (1196 150);
PAINT MONO (1196 150);
FORCEPROP 2 LAST PATH I56
J 0
(1200 200);
DISPLAY 1.021277 (1200 200);
DISPLAY INVISIBLE (1200 200);
FORCEPROP 2 LAST CDS_LIB standard
J 0
(1450 150);
DISPLAY INVISIBLE (1450 150);
FORCEPROP 1 LAST COMMENT_BODY TRUE
J 2
(1495 55);
DISPLAY 0.872340 (1495 55);
PAINT GREEN (1495 55);
DISPLAY INVISIBLE (1495 55);
FORCEPROP 1 LAST OFFPAGE TRUE
J 2
(1125 25);
DISPLAY 0.872340 (1125 25);
PAINT AQUA (1125 25);
DISPLAY INVISIBLE (1125 25);
FORCEADD OFFPAGE..2
R 2
(1450 300);
FORCEPROP 2 LAST $XR0 61 
J 0
(1196 300);
DISPLAY 0.638298 (1196 300);
PAINT MONO (1196 300);
FORCEPROP 2 LAST PATH I57
J 0
(1200 350);
DISPLAY 1.021277 (1200 350);
DISPLAY INVISIBLE (1200 350);
FORCEPROP 1 LAST OFFPAGE TRUE
J 2
(1125 175);
DISPLAY 0.872340 (1125 175);
PAINT AQUA (1125 175);
DISPLAY INVISIBLE (1125 175);
FORCEPROP 1 LAST COMMENT_BODY TRUE
J 2
(1495 205);
DISPLAY 0.872340 (1495 205);
PAINT GREEN (1495 205);
DISPLAY INVISIBLE (1495 205);
FORCEPROP 2 LAST CDS_LIB standard
J 0
(1450 300);
DISPLAY INVISIBLE (1450 300);
FORCEADD OFFPAGE..5
(1450 250);
FORCEPROP 2 LAST $XR0 61 
J 0
(1196 250);
DISPLAY 0.638298 (1196 250);
PAINT MONO (1196 250);
FORCEPROP 2 LAST PATH I58
J 0
(1200 300);
DISPLAY 1.021277 (1200 300);
DISPLAY INVISIBLE (1200 300);
FORCEPROP 1 LAST OFFPAGE TRUE
J 0
(1775 125);
DISPLAY 0.872340 (1775 125);
PAINT AQUA (1775 125);
DISPLAY INVISIBLE (1775 125);
FORCEPROP 1 LAST COMMENT_BODY TRUE
J 0
(1550 175);
DISPLAY 1.170213 (1550 175);
PAINT GREEN (1550 175);
DISPLAY INVISIBLE (1550 175);
FORCEPROP 2 LAST CDS_LIB standard
J 0
(1450 250);
DISPLAY INVISIBLE (1450 250);
FORCEADD OFFPAGE..1
(1450 550);
FORCEPROP 2 LAST $XR0 176 
J 0
(1198 550);
DISPLAY 0.638298 (1198 550);
PAINT MONO (1198 550);
FORCEPROP 2 LAST PATH I59
J 0
(1200 600);
DISPLAY 1.021277 (1200 600);
DISPLAY INVISIBLE (1200 600);
FORCEPROP 2 LAST CDS_LIB standard
J 0
(1450 550);
DISPLAY INVISIBLE (1450 550);
FORCEPROP 1 LAST COMMENT_BODY TRUE
J 0
(1575 450);
DISPLAY 0.872340 (1575 450);
PAINT GREEN (1575 450);
DISPLAY INVISIBLE (1575 450);
FORCEPROP 1 LAST OFFPAGE TRUE
J 0
(1775 425);
DISPLAY 0.872340 (1775 425);
PAINT AQUA (1775 425);
DISPLAY INVISIBLE (1775 425);
FORCEADD OFFPAGE..2
R 2
(-3300 -750);
FORCEPROP 2 LAST $XR0 61 
J 0
(-3554 -750);
DISPLAY 0.638298 (-3554 -750);
PAINT MONO (-3554 -750);
FORCEPROP 2 LAST CDS_LIB standard
J 0
(-3300 -750);
DISPLAY INVISIBLE (-3300 -750);
FORCEPROP 1 LAST COMMENT_BODY TRUE
J 2
(-3255 -845);
DISPLAY 0.872340 (-3255 -845);
PAINT GREEN (-3255 -845);
DISPLAY INVISIBLE (-3255 -845);
FORCEPROP 1 LAST OFFPAGE TRUE
J 2
(-3625 -875);
DISPLAY 0.872340 (-3625 -875);
PAINT AQUA (-3625 -875);
DISPLAY INVISIBLE (-3625 -875);
FORCEPROP 2 LAST PATH I6
J 0
(-3550 -700);
DISPLAY 1.021277 (-3550 -700);
DISPLAY INVISIBLE (-3550 -700);
FORCEADD OFFPAGE..1
(1450 600);
FORCEPROP 2 LAST $XR0 176 
J 0
(1198 600);
DISPLAY 0.638298 (1198 600);
PAINT MONO (1198 600);
FORCEPROP 2 LAST PATH I60
J 0
(1200 650);
DISPLAY 1.021277 (1200 650);
DISPLAY INVISIBLE (1200 650);
FORCEPROP 1 LAST OFFPAGE TRUE
J 0
(1775 475);
DISPLAY 0.872340 (1775 475);
PAINT AQUA (1775 475);
DISPLAY INVISIBLE (1775 475);
FORCEPROP 1 LAST COMMENT_BODY TRUE
J 0
(1575 500);
DISPLAY 0.872340 (1575 500);
PAINT GREEN (1575 500);
DISPLAY INVISIBLE (1575 500);
FORCEPROP 2 LAST CDS_LIB standard
J 0
(1450 600);
DISPLAY INVISIBLE (1450 600);
FORCEADD OFFPAGE..1
(1450 700);
FORCEPROP 2 LAST $XR0 177 
J 0
(1198 700);
DISPLAY 0.638298 (1198 700);
PAINT MONO (1198 700);
FORCEPROP 2 LAST PATH I61
J 0
(1200 750);
DISPLAY 1.021277 (1200 750);
DISPLAY INVISIBLE (1200 750);
FORCEPROP 2 LAST CDS_LIB standard
J 0
(1450 700);
DISPLAY INVISIBLE (1450 700);
FORCEPROP 1 LAST COMMENT_BODY TRUE
J 0
(1575 600);
DISPLAY 0.872340 (1575 600);
PAINT GREEN (1575 600);
DISPLAY INVISIBLE (1575 600);
FORCEPROP 1 LAST OFFPAGE TRUE
J 0
(1775 575);
DISPLAY 0.872340 (1775 575);
PAINT AQUA (1775 575);
DISPLAY INVISIBLE (1775 575);
FORCEADD OFFPAGE..1
(1450 750);
FORCEPROP 2 LAST $XR0 177 
J 0
(1198 750);
DISPLAY 0.638298 (1198 750);
PAINT MONO (1198 750);
FORCEPROP 2 LAST PATH I62
J 0
(1200 800);
DISPLAY 1.021277 (1200 800);
DISPLAY INVISIBLE (1200 800);
FORCEPROP 1 LAST OFFPAGE TRUE
J 0
(1775 625);
DISPLAY 0.872340 (1775 625);
PAINT AQUA (1775 625);
DISPLAY INVISIBLE (1775 625);
FORCEPROP 1 LAST COMMENT_BODY TRUE
J 0
(1575 650);
DISPLAY 0.872340 (1575 650);
PAINT GREEN (1575 650);
DISPLAY INVISIBLE (1575 650);
FORCEPROP 2 LAST CDS_LIB standard
J 0
(1450 750);
DISPLAY INVISIBLE (1450 750);
FORCEADD OFFPAGE..2
R 2
(1450 900);
FORCEPROP 2 LAST $XR0 61 
J 0
(1196 900);
DISPLAY 0.638298 (1196 900);
PAINT MONO (1196 900);
FORCEPROP 2 LAST PATH I63
J 0
(1200 950);
DISPLAY 1.021277 (1200 950);
DISPLAY INVISIBLE (1200 950);
FORCEPROP 1 LAST OFFPAGE TRUE
J 2
(1125 775);
DISPLAY 0.872340 (1125 775);
PAINT AQUA (1125 775);
DISPLAY INVISIBLE (1125 775);
FORCEPROP 1 LAST COMMENT_BODY TRUE
J 2
(1495 805);
DISPLAY 0.872340 (1495 805);
PAINT GREEN (1495 805);
DISPLAY INVISIBLE (1495 805);
FORCEPROP 2 LAST CDS_LIB standard
J 0
(1450 900);
DISPLAY INVISIBLE (1450 900);
FORCEADD OFFPAGE..5
(1450 850);
FORCEPROP 2 LAST $XR0 61 
J 0
(1196 850);
DISPLAY 0.638298 (1196 850);
PAINT MONO (1196 850);
FORCEPROP 2 LAST PATH I64
J 0
(1200 900);
DISPLAY 1.021277 (1200 900);
DISPLAY INVISIBLE (1200 900);
FORCEPROP 1 LAST OFFPAGE TRUE
J 0
(1775 725);
DISPLAY 0.872340 (1775 725);
PAINT AQUA (1775 725);
DISPLAY INVISIBLE (1775 725);
FORCEPROP 1 LAST COMMENT_BODY TRUE
J 0
(1550 775);
DISPLAY 1.170213 (1550 775);
PAINT GREEN (1550 775);
DISPLAY INVISIBLE (1550 775);
FORCEPROP 2 LAST CDS_LIB standard
J 0
(1450 850);
DISPLAY INVISIBLE (1450 850);
FORCEADD OFFPAGE..2
R 2
(1450 1050);
FORCEPROP 2 LAST $XR0 61 
J 0
(1196 1050);
DISPLAY 0.638298 (1196 1050);
PAINT MONO (1196 1050);
FORCEPROP 2 LAST PATH I65
J 0
(1200 1100);
DISPLAY 1.021277 (1200 1100);
DISPLAY INVISIBLE (1200 1100);
FORCEPROP 1 LAST OFFPAGE TRUE
J 2
(1125 925);
DISPLAY 0.872340 (1125 925);
PAINT AQUA (1125 925);
DISPLAY INVISIBLE (1125 925);
FORCEPROP 1 LAST COMMENT_BODY TRUE
J 2
(1495 955);
DISPLAY 0.872340 (1495 955);
PAINT GREEN (1495 955);
DISPLAY INVISIBLE (1495 955);
FORCEPROP 2 LAST CDS_LIB standard
J 0
(1450 1050);
DISPLAY INVISIBLE (1450 1050);
FORCEADD OFFPAGE..5
(1450 1000);
FORCEPROP 2 LAST $XR0 61 
J 0
(1196 1000);
DISPLAY 0.638298 (1196 1000);
PAINT MONO (1196 1000);
FORCEPROP 2 LAST PATH I66
J 0
(1200 1050);
DISPLAY 1.021277 (1200 1050);
DISPLAY INVISIBLE (1200 1050);
FORCEPROP 1 LAST OFFPAGE TRUE
J 0
(1775 875);
DISPLAY 0.872340 (1775 875);
PAINT AQUA (1775 875);
DISPLAY INVISIBLE (1775 875);
FORCEPROP 1 LAST COMMENT_BODY TRUE
J 0
(1550 925);
DISPLAY 1.170213 (1550 925);
PAINT GREEN (1550 925);
DISPLAY INVISIBLE (1550 925);
FORCEPROP 2 LAST CDS_LIB standard
J 0
(1450 1000);
DISPLAY INVISIBLE (1450 1000);
FORCEADD OFFPAGE..1
(1450 1550);
FORCEPROP 2 LAST $XR0 177 
J 0
(1198 1550);
DISPLAY 0.638298 (1198 1550);
PAINT MONO (1198 1550);
FORCEPROP 2 LAST PATH I69
J 0
(1200 1600);
DISPLAY 1.021277 (1200 1600);
DISPLAY INVISIBLE (1200 1600);
FORCEPROP 1 LAST OFFPAGE TRUE
J 0
(1775 1425);
DISPLAY 0.872340 (1775 1425);
PAINT AQUA (1775 1425);
DISPLAY INVISIBLE (1775 1425);
FORCEPROP 1 LAST COMMENT_BODY TRUE
J 0
(1575 1450);
DISPLAY 0.872340 (1575 1450);
PAINT GREEN (1575 1450);
DISPLAY INVISIBLE (1575 1450);
FORCEPROP 2 LAST CDS_LIB standard
J 0
(1450 1550);
DISPLAY INVISIBLE (1450 1550);
FORCEADD OFFPAGE..5
(-3300 -650);
FORCEPROP 2 LAST $XR0 61 
J 0
(-3554 -650);
DISPLAY 0.638298 (-3554 -650);
PAINT MONO (-3554 -650);
FORCEPROP 2 LAST CDS_LIB standard
J 0
(-3300 -650);
DISPLAY INVISIBLE (-3300 -650);
FORCEPROP 1 LAST COMMENT_BODY TRUE
J 0
(-3200 -725);
DISPLAY 1.170213 (-3200 -725);
PAINT GREEN (-3200 -725);
DISPLAY INVISIBLE (-3200 -725);
FORCEPROP 1 LAST OFFPAGE TRUE
J 0
(-2975 -775);
DISPLAY 0.872340 (-2975 -775);
PAINT AQUA (-2975 -775);
DISPLAY INVISIBLE (-2975 -775);
FORCEPROP 2 LAST PATH I7
J 0
(-3550 -600);
DISPLAY 1.021277 (-3550 -600);
DISPLAY INVISIBLE (-3550 -600);
FORCEADD OFFPAGE..1
(1450 1450);
FORCEPROP 2 LAST $XR0 176 
J 0
(1198 1450);
DISPLAY 0.638298 (1198 1450);
PAINT MONO (1198 1450);
FORCEPROP 2 LAST PATH I70
J 0
(1200 1500);
DISPLAY 1.021277 (1200 1500);
DISPLAY INVISIBLE (1200 1500);
FORCEPROP 1 LAST OFFPAGE TRUE
J 0
(1775 1325);
DISPLAY 0.872340 (1775 1325);
PAINT AQUA (1775 1325);
DISPLAY INVISIBLE (1775 1325);
FORCEPROP 1 LAST COMMENT_BODY TRUE
J 0
(1575 1350);
DISPLAY 0.872340 (1575 1350);
PAINT GREEN (1575 1350);
DISPLAY INVISIBLE (1575 1350);
FORCEPROP 2 LAST CDS_LIB standard
J 0
(1450 1450);
DISPLAY INVISIBLE (1450 1450);
FORCEADD OFFPAGE..1
(1450 1400);
FORCEPROP 2 LAST $XR0 176 
J 0
(1198 1400);
DISPLAY 0.638298 (1198 1400);
PAINT MONO (1198 1400);
FORCEPROP 2 LAST PATH I71
J 0
(1200 1450);
DISPLAY 1.021277 (1200 1450);
DISPLAY INVISIBLE (1200 1450);
FORCEPROP 2 LAST CDS_LIB standard
J 0
(1450 1400);
DISPLAY INVISIBLE (1450 1400);
FORCEPROP 1 LAST COMMENT_BODY TRUE
J 0
(1575 1300);
DISPLAY 0.872340 (1575 1300);
PAINT GREEN (1575 1300);
DISPLAY INVISIBLE (1575 1300);
FORCEPROP 1 LAST OFFPAGE TRUE
J 0
(1775 1275);
DISPLAY 0.872340 (1775 1275);
PAINT AQUA (1775 1275);
DISPLAY INVISIBLE (1775 1275);
FORCEADD OFFPAGE..1
(1450 1600);
FORCEPROP 2 LAST $XR0 177 
J 0
(1198 1600);
DISPLAY 0.638298 (1198 1600);
PAINT MONO (1198 1600);
FORCEPROP 2 LAST PATH I72
J 0
(1200 1650);
DISPLAY 1.021277 (1200 1650);
DISPLAY INVISIBLE (1200 1650);
FORCEPROP 2 LAST CDS_LIB standard
J 0
(1450 1600);
DISPLAY INVISIBLE (1450 1600);
FORCEPROP 1 LAST COMMENT_BODY TRUE
J 0
(1575 1500);
DISPLAY 0.872340 (1575 1500);
PAINT GREEN (1575 1500);
DISPLAY INVISIBLE (1575 1500);
FORCEPROP 1 LAST OFFPAGE TRUE
J 0
(1775 1475);
DISPLAY 0.872340 (1775 1475);
PAINT AQUA (1775 1475);
DISPLAY INVISIBLE (1775 1475);
FORCEADD OFFPAGE..2
R 2
(1450 1750);
FORCEPROP 2 LAST $XR0 61 
J 0
(1196 1750);
DISPLAY 0.638298 (1196 1750);
PAINT MONO (1196 1750);
FORCEPROP 2 LAST PATH I73
J 0
(1200 1800);
DISPLAY 1.021277 (1200 1800);
DISPLAY INVISIBLE (1200 1800);
FORCEPROP 2 LAST CDS_LIB standard
J 0
(1450 1750);
DISPLAY INVISIBLE (1450 1750);
FORCEPROP 1 LAST COMMENT_BODY TRUE
J 2
(1495 1655);
DISPLAY 0.872340 (1495 1655);
PAINT GREEN (1495 1655);
DISPLAY INVISIBLE (1495 1655);
FORCEPROP 1 LAST OFFPAGE TRUE
J 2
(1125 1625);
DISPLAY 0.872340 (1125 1625);
PAINT AQUA (1125 1625);
DISPLAY INVISIBLE (1125 1625);
FORCEADD OFFPAGE..5
(1450 1700);
FORCEPROP 2 LAST $XR0 61 
J 0
(1196 1700);
DISPLAY 0.638298 (1196 1700);
PAINT MONO (1196 1700);
FORCEPROP 2 LAST PATH I74
J 0
(1200 1750);
DISPLAY 1.021277 (1200 1750);
DISPLAY INVISIBLE (1200 1750);
FORCEPROP 2 LAST CDS_LIB standard
J 0
(1450 1700);
DISPLAY INVISIBLE (1450 1700);
FORCEPROP 1 LAST COMMENT_BODY TRUE
J 0
(1550 1625);
DISPLAY 1.170213 (1550 1625);
PAINT GREEN (1550 1625);
DISPLAY INVISIBLE (1550 1625);
FORCEPROP 1 LAST OFFPAGE TRUE
J 0
(1775 1575);
DISPLAY 0.872340 (1775 1575);
PAINT AQUA (1775 1575);
DISPLAY INVISIBLE (1775 1575);
FORCEADD OFFPAGE..5
(1450 1850);
FORCEPROP 2 LAST $XR0 61 
J 0
(1196 1850);
DISPLAY 0.638298 (1196 1850);
PAINT MONO (1196 1850);
FORCEPROP 2 LAST PATH I75
J 0
(1200 1900);
DISPLAY 1.021277 (1200 1900);
DISPLAY INVISIBLE (1200 1900);
FORCEPROP 1 LAST OFFPAGE TRUE
J 0
(1775 1725);
DISPLAY 0.872340 (1775 1725);
PAINT AQUA (1775 1725);
DISPLAY INVISIBLE (1775 1725);
FORCEPROP 1 LAST COMMENT_BODY TRUE
J 0
(1550 1775);
DISPLAY 1.170213 (1550 1775);
PAINT GREEN (1550 1775);
DISPLAY INVISIBLE (1550 1775);
FORCEPROP 2 LAST CDS_LIB standard
J 0
(1450 1850);
DISPLAY INVISIBLE (1450 1850);
FORCEADD OFFPAGE..2
R 2
(1450 1900);
FORCEPROP 2 LAST $XR0 61 
J 0
(1196 1900);
DISPLAY 0.638298 (1196 1900);
PAINT MONO (1196 1900);
FORCEPROP 2 LAST PATH I76
J 0
(1200 1950);
DISPLAY 1.021277 (1200 1950);
DISPLAY INVISIBLE (1200 1950);
FORCEPROP 1 LAST OFFPAGE TRUE
J 2
(1125 1775);
DISPLAY 0.872340 (1125 1775);
PAINT AQUA (1125 1775);
DISPLAY INVISIBLE (1125 1775);
FORCEPROP 1 LAST COMMENT_BODY TRUE
J 2
(1495 1805);
DISPLAY 0.872340 (1495 1805);
PAINT GREEN (1495 1805);
DISPLAY INVISIBLE (1495 1805);
FORCEPROP 2 LAST CDS_LIB standard
J 0
(1450 1900);
DISPLAY INVISIBLE (1450 1900);
FORCEADD OFFPAGE..2
R 2
(1450 1300);
FORCEPROP 2 LAST $XR0 148 
J 0
(1165 1300);
DISPLAY 0.638298 (1165 1300);
PAINT MONO (1165 1300);
FORCEPROP 2 LAST CDS_LIB standard
J 0
(1450 1300);
DISPLAY INVISIBLE (1450 1300);
FORCEPROP 2 LAST PATH I78
J 0
(1175 1350);
DISPLAY 1.021277 (1175 1350);
DISPLAY INVISIBLE (1175 1350);
FORCEPROP 1 LAST COMMENT_BODY TRUE
J 2
(1495 1205);
DISPLAY 0.872340 (1495 1205);
PAINT GREEN (1495 1205);
DISPLAY INVISIBLE (1495 1205);
FORCEPROP 1 LAST OFFPAGE TRUE
J 2
(1125 1175);
DISPLAY 0.872340 (1125 1175);
PAINT AQUA (1125 1175);
DISPLAY INVISIBLE (1125 1175);
FORCEADD OFFPAGE..5
(-3300 -350);
FORCEPROP 2 LAST $XR0 148 
J 0
(-3585 -350);
DISPLAY 0.638298 (-3585 -350);
PAINT MONO (-3585 -350);
FORCEPROP 2 LAST CDS_LIB standard
J 0
(-3300 -350);
DISPLAY INVISIBLE (-3300 -350);
FORCEPROP 2 LAST PATH I79
J 0
(-3575 -300);
DISPLAY 1.021277 (-3575 -300);
DISPLAY INVISIBLE (-3575 -300);
FORCEPROP 1 LAST OFFPAGE TRUE
J 0
(-2975 -475);
DISPLAY 0.872340 (-2975 -475);
PAINT AQUA (-2975 -475);
DISPLAY INVISIBLE (-2975 -475);
FORCEPROP 1 LAST COMMENT_BODY TRUE
J 0
(-3200 -425);
DISPLAY 1.170213 (-3200 -425);
PAINT GREEN (-3200 -425);
DISPLAY INVISIBLE (-3200 -425);
FORCEADD OFFPAGE..2
R 2
(-3300 -600);
FORCEPROP 2 LAST $XR0 61 
J 0
(-3554 -600);
DISPLAY 0.638298 (-3554 -600);
PAINT MONO (-3554 -600);
FORCEPROP 2 LAST CDS_LIB standard
J 0
(-3300 -600);
DISPLAY INVISIBLE (-3300 -600);
FORCEPROP 1 LAST COMMENT_BODY TRUE
J 2
(-3255 -695);
DISPLAY 0.872340 (-3255 -695);
PAINT GREEN (-3255 -695);
DISPLAY INVISIBLE (-3255 -695);
FORCEPROP 1 LAST OFFPAGE TRUE
J 2
(-3625 -725);
DISPLAY 0.872340 (-3625 -725);
PAINT AQUA (-3625 -725);
DISPLAY INVISIBLE (-3625 -725);
FORCEPROP 2 LAST PATH I8
J 0
(-3550 -550);
DISPLAY 1.021277 (-3550 -550);
DISPLAY INVISIBLE (-3550 -550);
FORCEADD OFFPAGE..1
(-3300 1250);
FORCEPROP 2 LAST $XR0 150 
J 0
(-3552 1250);
DISPLAY 0.638298 (-3552 1250);
PAINT MONO (-3552 1250);
FORCEPROP 1 LAST OFFPAGE TRUE
J 0
(-2975 1125);
DISPLAY 0.872340 (-2975 1125);
PAINT AQUA (-2975 1125);
DISPLAY INVISIBLE (-2975 1125);
FORCEPROP 1 LAST COMMENT_BODY TRUE
J 0
(-3175 1150);
DISPLAY 0.872340 (-3175 1150);
PAINT GREEN (-3175 1150);
DISPLAY INVISIBLE (-3175 1150);
FORCEPROP 2 LAST CDS_LIB standard
J 0
(-3300 1250);
DISPLAY INVISIBLE (-3300 1250);
FORCEPROP 2 LAST PATH I80
J 0
(-3250 1325);
DISPLAY 1.021277 (-3250 1325);
DISPLAY INVISIBLE (-3250 1325);
FORCEADD OFFPAGE..1
(-3300 1100);
FORCEPROP 2 LAST $XR0 149 
J 0
(-3552 1100);
DISPLAY 0.638298 (-3552 1100);
PAINT MONO (-3552 1100);
FORCEPROP 1 LAST OFFPAGE TRUE
J 0
(-2975 975);
DISPLAY 0.872340 (-2975 975);
PAINT AQUA (-2975 975);
DISPLAY INVISIBLE (-2975 975);
FORCEPROP 1 LAST COMMENT_BODY TRUE
J 0
(-3175 1000);
DISPLAY 0.872340 (-3175 1000);
PAINT GREEN (-3175 1000);
DISPLAY INVISIBLE (-3175 1000);
FORCEPROP 2 LAST CDS_LIB standard
J 0
(-3300 1100);
DISPLAY INVISIBLE (-3300 1100);
FORCEPROP 2 LAST PATH I81
J 0
(-3250 1175);
DISPLAY 1.021277 (-3250 1175);
DISPLAY INVISIBLE (-3250 1175);
FORCEADD OFFPAGE..1
(1450 -300);
FORCEPROP 2 LAST $XR0 149 
J 0
(1198 -300);
DISPLAY 0.638298 (1198 -300);
PAINT MONO (1198 -300);
FORCEPROP 2 LAST PATH I84
J 0
(1500 -225);
DISPLAY 1.021277 (1500 -225);
DISPLAY INVISIBLE (1500 -225);
FORCEPROP 1 LAST OFFPAGE TRUE
J 0
(1775 -425);
DISPLAY 0.872340 (1775 -425);
PAINT AQUA (1775 -425);
DISPLAY INVISIBLE (1775 -425);
FORCEPROP 1 LAST COMMENT_BODY TRUE
J 0
(1575 -400);
DISPLAY 0.872340 (1575 -400);
PAINT GREEN (1575 -400);
DISPLAY INVISIBLE (1575 -400);
FORCEPROP 2 LAST CDS_LIB standard
J 0
(1450 -300);
DISPLAY INVISIBLE (1450 -300);
FORCEADD OFFPAGE..1
(1450 -450);
FORCEPROP 2 LAST $XR0 150 
J 0
(1198 -450);
DISPLAY 0.638298 (1198 -450);
PAINT MONO (1198 -450);
FORCEPROP 2 LAST CDS_LIB standard
J 0
(1450 -450);
DISPLAY INVISIBLE (1450 -450);
FORCEPROP 1 LAST COMMENT_BODY TRUE
J 0
(1575 -550);
DISPLAY 0.872340 (1575 -550);
PAINT GREEN (1575 -550);
DISPLAY INVISIBLE (1575 -550);
FORCEPROP 1 LAST OFFPAGE TRUE
J 0
(1775 -575);
DISPLAY 0.872340 (1775 -575);
PAINT AQUA (1775 -575);
DISPLAY INVISIBLE (1775 -575);
FORCEPROP 2 LAST PATH I85
J 0
(1500 -375);
DISPLAY 1.021277 (1500 -375);
DISPLAY INVISIBLE (1500 -375);
FORCEADD OFFPAGE..2
R 2
(1450 1150);
FORCEPROP 2 LAST $XR0 147 
J 0
(1165 1150);
DISPLAY 0.638298 (1165 1150);
PAINT MONO (1165 1150);
FORCEPROP 1 LAST OFFPAGE TRUE
J 2
(1125 1025);
DISPLAY 0.872340 (1125 1025);
PAINT AQUA (1125 1025);
DISPLAY INVISIBLE (1125 1025);
FORCEPROP 1 LAST COMMENT_BODY TRUE
J 2
(1495 1055);
DISPLAY 0.872340 (1495 1055);
PAINT GREEN (1495 1055);
DISPLAY INVISIBLE (1495 1055);
FORCEPROP 2 LAST PATH I86
J 0
(1500 1225);
DISPLAY 1.021277 (1500 1225);
DISPLAY INVISIBLE (1500 1225);
FORCEPROP 2 LAST CDS_LIB standard
J 0
(1450 1150);
DISPLAY INVISIBLE (1450 1150);
FORCEADD OFFPAGE..5
(-3300 -500);
FORCEPROP 2 LAST $XR0 147 
J 0
(-3585 -500);
DISPLAY 0.638298 (-3585 -500);
PAINT MONO (-3585 -500);
FORCEPROP 1 LAST COMMENT_BODY TRUE
J 0
(-3200 -575);
DISPLAY 1.170213 (-3200 -575);
PAINT GREEN (-3200 -575);
DISPLAY INVISIBLE (-3200 -575);
FORCEPROP 1 LAST OFFPAGE TRUE
J 0
(-2975 -625);
DISPLAY 0.872340 (-2975 -625);
PAINT AQUA (-2975 -625);
DISPLAY INVISIBLE (-2975 -625);
FORCEPROP 2 LAST PATH I87
J 0
(-3250 -425);
DISPLAY 1.021277 (-3250 -425);
DISPLAY INVISIBLE (-3250 -425);
FORCEPROP 2 LAST CDS_LIB standard
J 0
(-3300 -500);
DISPLAY INVISIBLE (-3300 -500);
FORCEADD QUANTA_TITLE_BLOCK_C..1
(4675 -3325);
FORCEPROP 0 LAST CDS_CON_LAST_MODIFIED Fri Aug 25 14:02:02 2023
J 0
(2790 -3310);
PAINT MONO (2790 -3310);
DISPLAY INVISIBLE (2790 -3310);
FORCEPROP 2 LAST CUSTOM_TXT_CDS <XR_PAGE_TITLE>
J 0
(-3215 1925);
DISPLAY 0.638298 (-3215 1925);
PAINT PINK (-3215 1925);
DISPLAY INVISIBLE (-3215 1925);
FORCEPROP 2 LAST CUSTOM_TXT_CDS <CON_PAGE_NUM> OF <CON_TOTAL_PAGES>
J 0
(4229 -3307);
DISPLAY 0.978723 (4229 -3307);
FORCEPROP 2 LAST CUSTOM_TXT_CDS <CON_LAST_MODIFIED>
J 0
(2800 -3300);
DISPLAY 0.978723 (2800 -3300);
FORCEPROP 2 LAST CUSTOM_TXT_CDS <Q_NUMBER>
J 0
(3272 -3222);
DISPLAY 1.212766 (3272 -3222);
FORCEPROP 2 LAST CUSTOM_TXT_CDS <Q_PROJ>
J 0
(2293 -3223);
DISPLAY 1.212766 (2293 -3223);
FORCEPROP 2 LAST CUSTOM_TXT_CDS <NAME_1>
J 0
(1500 -3150);
FORCEPROP 2 LAST CUSTOM_TXT_CDS <NAME_2>
J 0
(1500 -3275);
FORCEPROP 2 LAST CUSTOM_TXT_CDS <Q_REV>
J 0
(4491 -3222);
DISPLAY 1.212766 (4491 -3222);
FORCEPROP 1 LAST Q_TITLE PCIE - CPU1_EXAMAX_P2/P3_X16
J 0
(-4600 -3275);
DISPLAY 1.957447 (-4600 -3275);
PAINT GREEN (-4600 -3275);
FORCEPROP 1 LAST Q_DEPT 
J 1
(912 -3276);
DISPLAY 1.957447 (912 -3276);
PAINT GREEN (912 -3276);
FORCEPROP 2 LAST CDS_XR_PAGE_TITLE CR-141 : @S9S_MB_2U_LIB.S9S_MB_2U(SCH_1):PAGE141
J 0
(-3215 1925);
DISPLAY 0.638298 (-3215 1925);
PAINT PINK (-3215 1925);
DISPLAY INVISIBLE (-3215 1925);
FORCEPROP 2 LAST CDS_LIB pure_quanta
J 0
(4675 -3325);
PAINT MONO (4675 -3325);
DISPLAY INVISIBLE (4675 -3325);
FORCEPROP 1 LAST CDS_LMAN_SYM_OUTLINE -9475,6775,100,-125
J 0
(4675 -3325);
DISPLAY 0.468085 (4675 -3325);
PAINT GREEN (4675 -3325);
DISPLAY INVISIBLE (4675 -3325);
FORCEPROP 2 LAST PAGE_BORDER TRUE
J 0
(-3215 1925);
DISPLAY 0.638298 (-3215 1925);
PAINT PINK (-3215 1925);
DISPLAY INVISIBLE (-3215 1925);
FORCEPROP 1 LAST COMMENT_BODY TRUE
J 0
(4687 -3338);
DISPLAY 0.978723 (4687 -3338);
PAINT GREEN (4687 -3338);
DISPLAY INVISIBLE (4687 -3338);
WIRE 16 -1 (2525 -1100)(2525 -1450);
WIRE 16 -1 (2525 -950)(2525 -1100);
WIRE 16 -1 (2750 -1100)(2525 -1100);
WIRE 16 -1 (-2200 -1150)(-2200 -1450);
WIRE 16 -1 (-2200 -1000)(-2200 -1150);
WIRE 16 -1 (-2025 -1150)(-2200 -1150);
WIRE 16 -1 (-2025 -500)(-3250 -500);
FORCEPROP 2 LAST SIG_NAME GPU_BASE_HMC_READY
J 0
(-3135 -490);
DISPLAY 0.638298 (-3135 -490);
WIRE 16 -1 (-2025 -600)(-3250 -600);
FORCEPROP 2 LAST SIG_NAME P5E_CPU1_PE3_RX_DN<11>
J 0
(-3135 -590);
DISPLAY 0.638298 (-3135 -590);
WIRE 16 -1 (-2025 -650)(-3250 -650);
FORCEPROP 2 LAST SIG_NAME P5E_CPU1_PE3_RX_DP<11>
J 0
(-3135 -640);
DISPLAY 0.638298 (-3135 -640);
WIRE 16 -1 (-2025 -750)(-3250 -750);
FORCEPROP 2 LAST SIG_NAME P5E_CPU1_PE2_RX_DP<11>
J 0
(-3135 -740);
DISPLAY 0.638298 (-3135 -740);
WIRE 16 -1 (-2025 -800)(-3250 -800);
FORCEPROP 2 LAST SIG_NAME P5E_CPU1_PE2_RX_DN<11>
J 0
(-3135 -790);
DISPLAY 0.638298 (-3135 -790);
WIRE 16 -1 (-2025 1900)(-2200 1900);
WIRE 16 -1 (-2200 1900)(-2200 1750);
WIRE 16 -1 (-2025 1750)(-2200 1750);
WIRE 16 -1 (-2200 1750)(-2200 1600);
WIRE 16 -1 (-2025 1600)(-2200 1600);
WIRE 16 -1 (-2200 1600)(-2200 1450);
WIRE 16 -1 (-2025 1450)(-2200 1450);
WIRE 16 -1 (-2200 1450)(-2200 1300);
WIRE 16 -1 (-2025 1300)(-2200 1300);
WIRE 16 -1 (-2200 1300)(-2200 1050);
WIRE 16 -1 (-2025 1050)(-2200 1050);
WIRE 16 -1 (-2200 1050)(-2200 900);
WIRE 16 -1 (-2025 900)(-2200 900);
WIRE 16 -1 (-2200 900)(-2200 750);
WIRE 16 -1 (-2025 750)(-2200 750);
WIRE 16 -1 (-2200 750)(-2200 600);
WIRE 16 -1 (-2025 600)(-2200 600);
WIRE 16 -1 (-2200 600)(-2200 450);
WIRE 16 -1 (-2025 450)(-2200 450);
WIRE 16 -1 (-2200 450)(-2200 300);
WIRE 16 -1 (-2025 300)(-2200 300);
WIRE 16 -1 (-2200 300)(-2200 150);
WIRE 16 -1 (-2025 150)(-2200 150);
WIRE 16 -1 (-2200 150)(-2200 0);
WIRE 16 -1 (-2025 0)(-2200 0);
WIRE 16 -1 (-2025 -150)(-2200 -150);
WIRE 16 -1 (-2200 0)(-2200 -150);
WIRE 16 -1 (-2200 -150)(-2200 -300);
WIRE 16 -1 (-2025 -300)(-2200 -300);
WIRE 16 -1 (-2200 -300)(-2200 -550);
WIRE 16 -1 (-2025 -550)(-2200 -550);
WIRE 16 -1 (-2200 -700)(-2200 -550);
WIRE 16 -1 (-2025 -700)(-2200 -700);
WIRE 16 -1 (-2200 -850)(-2200 -700);
WIRE 16 -1 (-2025 -850)(-2200 -850);
WIRE 16 -1 (-2200 -850)(-2200 -1000);
WIRE 16 -1 (-2025 -1000)(-2200 -1000);
WIRE 16 -1 (2750 1050)(1500 1050);
FORCEPROP 2 LAST SIG_NAME P5E_CPU1_PE3_RX_DP<13>
J 0
(1615 1060);
DISPLAY 0.638298 (1615 1060);
WIRE 16 -1 (2750 1000)(1500 1000);
FORCEPROP 2 LAST SIG_NAME P5E_CPU1_PE3_RX_DN<13>
J 0
(1615 1010);
DISPLAY 0.638298 (1615 1010);
WIRE 16 -1 (2750 900)(1500 900);
FORCEPROP 2 LAST SIG_NAME P5E_CPU1_PE2_RX_DP<13>
J 0
(1615 910);
DISPLAY 0.638298 (1615 910);
WIRE 16 -1 (2750 1150)(1500 1150);
FORCEPROP 2 LAST SIG_NAME GPU_HMC_PRSNT_N
J 0
(1615 1160);
DISPLAY 0.638298 (1615 1160);
WIRE 16 -1 (2750 850)(1500 850);
FORCEPROP 2 LAST SIG_NAME P5E_CPU1_PE2_RX_DN<13>
J 0
(1615 860);
DISPLAY 0.638298 (1615 860);
WIRE 16 -1 (2750 750)(1500 750);
FORCEPROP 2 LAST SIG_NAME P5E_CPU1_PE3_TX_C_DN<13>
J 0
(1615 760);
DISPLAY 0.638298 (1615 760);
WIRE 16 -1 (2750 -950)(2525 -950);
WIRE 16 -1 (2525 -800)(2525 -950);
WIRE 16 -1 (2750 -800)(2525 -800);
WIRE 16 -1 (2525 -650)(2525 -800);
WIRE 16 -1 (2750 -650)(2525 -650);
WIRE 16 -1 (2525 -500)(2525 -650);
WIRE 16 -1 (2750 -500)(2525 -500);
WIRE 16 -1 (2525 -250)(2525 -500);
WIRE 16 -1 (2750 -250)(2525 -250);
WIRE 16 -1 (2525 -100)(2525 -250);
WIRE 16 -1 (2750 -100)(2525 -100);
WIRE 16 -1 (2525 50)(2525 -100);
WIRE 16 -1 (2750 50)(2525 50);
WIRE 16 -1 (2525 200)(2525 50);
WIRE 16 -1 (2750 200)(2525 200);
WIRE 16 -1 (2525 350)(2525 200);
WIRE 16 -1 (2750 350)(2525 350);
WIRE 16 -1 (2525 500)(2525 350);
WIRE 16 -1 (2750 500)(2525 500);
WIRE 16 -1 (2525 650)(2525 500);
WIRE 16 -1 (2750 650)(2525 650);
WIRE 16 -1 (2525 800)(2525 650);
WIRE 16 -1 (2750 800)(2525 800);
WIRE 16 -1 (2525 950)(2525 800);
WIRE 16 -1 (2750 950)(2525 950);
WIRE 16 -1 (2525 1100)(2525 950);
WIRE 16 -1 (2750 1100)(2525 1100);
WIRE 16 -1 (2525 1350)(2525 1100);
WIRE 16 -1 (2750 1350)(2525 1350);
WIRE 16 -1 (2525 1500)(2525 1350);
WIRE 16 -1 (2750 1500)(2525 1500);
WIRE 16 -1 (2525 1650)(2525 1500);
WIRE 16 -1 (2750 1650)(2525 1650);
WIRE 16 -1 (2525 1800)(2525 1650);
WIRE 16 -1 (2750 1800)(2525 1800);
WIRE 16 -1 (2525 1950)(2525 1800);
WIRE 16 -1 (2750 1950)(2525 1950);
WIRE 16 -1 (2750 1300)(1500 1300);
FORCEPROP 2 LAST SIG_NAME FM_SMB_1_ALERT_GPU_N
J 0
(1615 1310);
DISPLAY 0.638298 (1615 1310);
WIRE 16 -1 (2750 1400)(1500 1400);
FORCEPROP 2 LAST SIG_NAME P5E_CPU1_PE2_TX_C_DN<12>
J 0
(1615 1410);
DISPLAY 0.638298 (1615 1410);
WIRE 16 -1 (2750 700)(1500 700);
FORCEPROP 2 LAST SIG_NAME P5E_CPU1_PE3_TX_C_DP<13>
J 0
(1615 710);
DISPLAY 0.638298 (1615 710);
WIRE 16 -1 (-2025 1350)(-3250 1350);
FORCEPROP 2 LAST SIG_NAME P5E_CPU1_PE2_TX_C_DN<8>
J 0
(-3135 1360);
DISPLAY 0.638298 (-3135 1360);
WIRE 16 -1 (2750 -1000)(1500 -1000);
FORCEPROP 2 LAST SIG_NAME P5E_CPU1_PE2_TX_C_DP<15>
J 0
(1615 -990);
DISPLAY 0.638298 (1615 -990);
WIRE 16 -1 (-2025 950)(-3250 950);
FORCEPROP 2 LAST SIG_NAME P5E_CPU1_PE3_RX_DP<9>
J 0
(-3135 960);
DISPLAY 0.638298 (-3135 960);
WIRE 16 -1 (-2025 850)(-3250 850);
FORCEPROP 2 LAST SIG_NAME P5E_CPU1_PE2_RX_DP<9>
J 0
(-3135 860);
DISPLAY 0.638298 (-3135 860);
WIRE 16 -1 (-2025 800)(-3250 800);
FORCEPROP 2 LAST SIG_NAME P5E_CPU1_PE2_RX_DN<9>
J 0
(-3135 810);
DISPLAY 0.638298 (-3135 810);
WIRE 16 -1 (-2025 700)(-3250 700);
FORCEPROP 2 LAST SIG_NAME P5E_CPU1_PE3_TX_C_DN<9>
J 0
(-3135 710);
DISPLAY 0.638298 (-3135 710);
WIRE 16 -1 (-2025 650)(-3250 650);
FORCEPROP 2 LAST SIG_NAME P5E_CPU1_PE3_TX_C_DP<9>
J 0
(-3135 660);
DISPLAY 0.638298 (-3135 660);
WIRE 16 -1 (-2025 500)(-3250 500);
FORCEPROP 2 LAST SIG_NAME P5E_CPU1_PE2_TX_C_DN<9>
J 0
(-3135 510);
DISPLAY 0.638298 (-3135 510);
WIRE 16 -1 (2750 1900)(1500 1900);
FORCEPROP 2 LAST SIG_NAME P5E_CPU1_PE3_RX_DP<12>
J 0
(1615 1910);
DISPLAY 0.638298 (1615 1910);
WIRE 16 -1 (2750 1750)(1500 1750);
FORCEPROP 2 LAST SIG_NAME P5E_CPU1_PE2_RX_DP<12>
J 0
(1615 1760);
DISPLAY 0.638298 (1615 1760);
WIRE 16 -1 (2750 1700)(1500 1700);
FORCEPROP 2 LAST SIG_NAME P5E_CPU1_PE2_RX_DN<12>
J 0
(1615 1710);
DISPLAY 0.638298 (1615 1710);
WIRE 16 -1 (2750 1550)(1500 1550);
FORCEPROP 2 LAST SIG_NAME P5E_CPU1_PE3_TX_C_DP<12>
J 0
(1615 1560);
DISPLAY 0.638298 (1615 1560);
WIRE 16 -1 (2750 -1050)(1500 -1050);
FORCEPROP 2 LAST SIG_NAME P5E_CPU1_PE2_TX_C_DN<15>
J 0
(1615 -1040);
DISPLAY 0.638298 (1615 -1040);
WIRE 16 -1 (2750 -850)(1500 -850);
FORCEPROP 2 LAST SIG_NAME P5E_CPU1_PE3_TX_C_DN<15>
J 0
(1615 -840);
DISPLAY 0.638298 (1615 -840);
WIRE 16 -1 (2750 -900)(1500 -900);
FORCEPROP 2 LAST SIG_NAME P5E_CPU1_PE3_TX_C_DP<15>
J 0
(1615 -890);
DISPLAY 0.638298 (1615 -890);
WIRE 16 -1 (2750 -700)(1500 -700);
FORCEPROP 2 LAST SIG_NAME P5E_CPU1_PE2_RX_DP<15>
J 0
(1615 -690);
DISPLAY 0.638298 (1615 -690);
WIRE 16 -1 (2750 -750)(1500 -750);
FORCEPROP 2 LAST SIG_NAME P5E_CPU1_PE2_RX_DN<15>
J 0
(1615 -740);
DISPLAY 0.638298 (1615 -740);
WIRE 16 -1 (2750 -550)(1500 -550);
FORCEPROP 2 LAST SIG_NAME P5E_CPU1_PE3_RX_DP<15>
J 0
(1615 -540);
DISPLAY 0.638298 (1615 -540);
WIRE 16 -1 (2750 -600)(1500 -600);
FORCEPROP 2 LAST SIG_NAME P5E_CPU1_PE3_RX_DN<15>
J 0
(1615 -590);
DISPLAY 0.638298 (1615 -590);
WIRE 16 -1 (2750 -450)(1500 -450);
FORCEPROP 2 LAST SIG_NAME GPU_FPGA_EROT_RECOV_BUF_N
J 0
(1615 -440);
DISPLAY 0.638298 (1615 -440);
WIRE 16 -1 (2750 -300)(1500 -300);
FORCEPROP 2 LAST SIG_NAME GPU_FPGA_BOOT_EN_BUF
J 0
(1615 -290);
DISPLAY 0.638298 (1615 -290);
WIRE 16 -1 (2750 -200)(1500 -200);
FORCEPROP 2 LAST SIG_NAME P5E_CPU1_PE2_TX_C_DN<14>
J 0
(1615 -190);
DISPLAY 0.638298 (1615 -190);
WIRE 16 -1 (2750 -150)(1500 -150);
FORCEPROP 2 LAST SIG_NAME P5E_CPU1_PE2_TX_C_DP<14>
J 0
(1615 -140);
DISPLAY 0.638298 (1615 -140);
WIRE 16 -1 (2750 -50)(1500 -50);
FORCEPROP 2 LAST SIG_NAME P5E_CPU1_PE3_TX_C_DP<14>
J 0
(1615 -40);
DISPLAY 0.638298 (1615 -40);
WIRE 16 -1 (2750 0)(1500 0);
FORCEPROP 2 LAST SIG_NAME P5E_CPU1_PE3_TX_C_DN<14>
J 0
(1615 10);
DISPLAY 0.638298 (1615 10);
WIRE 16 -1 (2750 100)(1500 100);
FORCEPROP 2 LAST SIG_NAME P5E_CPU1_PE2_RX_DN<14>
J 0
(1615 110);
DISPLAY 0.638298 (1615 110);
WIRE 16 -1 (2750 150)(1500 150);
FORCEPROP 2 LAST SIG_NAME P5E_CPU1_PE2_RX_DP<14>
J 0
(1615 160);
DISPLAY 0.638298 (1615 160);
WIRE 16 -1 (2750 300)(1500 300);
FORCEPROP 2 LAST SIG_NAME P5E_CPU1_PE3_RX_DP<14>
J 0
(1615 310);
DISPLAY 0.638298 (1615 310);
WIRE 16 -1 (2750 250)(1500 250);
FORCEPROP 2 LAST SIG_NAME P5E_CPU1_PE3_RX_DN<14>
J 0
(1615 260);
DISPLAY 0.638298 (1615 260);
WIRE 16 -1 (2750 550)(1500 550);
FORCEPROP 2 LAST SIG_NAME P5E_CPU1_PE2_TX_C_DN<13>
J 0
(1615 560);
DISPLAY 0.638298 (1615 560);
WIRE 16 -1 (2750 600)(1500 600);
FORCEPROP 2 LAST SIG_NAME P5E_CPU1_PE2_TX_C_DP<13>
J 0
(1615 610);
DISPLAY 0.638298 (1615 610);
WIRE 16 -1 (2750 1450)(1500 1450);
FORCEPROP 2 LAST SIG_NAME P5E_CPU1_PE2_TX_C_DP<12>
J 0
(1615 1460);
DISPLAY 0.638298 (1615 1460);
WIRE 16 -1 (2750 1600)(1500 1600);
FORCEPROP 2 LAST SIG_NAME P5E_CPU1_PE3_TX_C_DN<12>
J 0
(1615 1610);
DISPLAY 0.638298 (1615 1610);
WIRE 16 -1 (2750 1850)(1500 1850);
FORCEPROP 2 LAST SIG_NAME P5E_CPU1_PE3_RX_DN<12>
J 0
(1615 1860);
DISPLAY 0.638298 (1615 1860);
WIRE 16 -1 (-2025 -100)(-3250 -100);
FORCEPROP 2 LAST SIG_NAME P5E_CPU1_PE3_TX_C_DP<10>
J 0
(-3135 -90);
DISPLAY 0.638298 (-3135 -90);
WIRE 16 -1 (-2025 200)(-3250 200);
FORCEPROP 2 LAST SIG_NAME P5E_CPU1_PE3_RX_DP<10>
J 0
(-3135 210);
DISPLAY 0.638298 (-3135 210);
WIRE 16 -1 (-2025 250)(-3250 250);
FORCEPROP 2 LAST SIG_NAME P5E_CPU1_PE3_RX_DN<10>
J 0
(-3135 260);
DISPLAY 0.638298 (-3135 260);
WIRE 16 -1 (-2025 1550)(-3250 1550);
FORCEPROP 2 LAST SIG_NAME P5E_CPU1_PE3_TX_C_DN<8>
J 0
(-3135 1560);
DISPLAY 0.638298 (-3135 1560);
WIRE 16 -1 (-2025 1250)(-3250 1250);
FORCEPROP 2 LAST SIG_NAME GPU_FPGA_EROT_RST_BUF_N
J 0
(-3135 1260);
DISPLAY 0.638298 (-3135 1260);
WIRE 16 -1 (-2025 1100)(-3250 1100);
FORCEPROP 2 LAST SIG_NAME GPU_BASE_STBY_EN_BUF
J 0
(-3135 1110);
DISPLAY 0.638298 (-3135 1110);
WIRE 16 -1 (-2025 1400)(-3250 1400);
FORCEPROP 2 LAST SIG_NAME P5E_CPU1_PE2_TX_C_DP<8>
J 0
(-3135 1410);
DISPLAY 0.638298 (-3135 1410);
WIRE 16 -1 (-2025 1000)(-3250 1000);
FORCEPROP 2 LAST SIG_NAME P5E_CPU1_PE3_RX_DN<9>
J 0
(-3135 1010);
DISPLAY 0.638298 (-3135 1010);
WIRE 16 -1 (-2025 550)(-3250 550);
FORCEPROP 2 LAST SIG_NAME P5E_CPU1_PE2_TX_C_DP<9>
J 0
(-3135 560);
DISPLAY 0.638298 (-3135 560);
WIRE 16 -1 (-2025 1500)(-3250 1500);
FORCEPROP 2 LAST SIG_NAME P5E_CPU1_PE3_TX_C_DP<8>
J 0
(-3135 1510);
DISPLAY 0.638298 (-3135 1510);
WIRE 16 -1 (-2025 1650)(-3250 1650);
FORCEPROP 2 LAST SIG_NAME P5E_CPU1_PE2_RX_DN<8>
J 0
(-3135 1660);
DISPLAY 0.638298 (-3135 1660);
WIRE 16 -1 (-2025 1700)(-3250 1700);
FORCEPROP 2 LAST SIG_NAME P5E_CPU1_PE2_RX_DP<8>
J 0
(-3135 1710);
DISPLAY 0.638298 (-3135 1710);
WIRE 16 -1 (-2025 50)(-3250 50);
FORCEPROP 2 LAST SIG_NAME P5E_CPU1_PE2_RX_DN<10>
J 0
(-3135 60);
DISPLAY 0.638298 (-3135 60);
WIRE 16 -1 (-2025 -50)(-3250 -50);
FORCEPROP 2 LAST SIG_NAME P5E_CPU1_PE3_TX_C_DN<10>
J 0
(-3135 -40);
DISPLAY 0.638298 (-3135 -40);
WIRE 16 -1 (-2025 -350)(-3250 -350);
FORCEPROP 2 LAST SIG_NAME FM_SMB_2_ALERT_GPU_N
J 0
(-3135 -340);
DISPLAY 0.638298 (-3135 -340);
WIRE 16 -1 (-2025 100)(-3250 100);
FORCEPROP 2 LAST SIG_NAME P5E_CPU1_PE2_RX_DP<10>
J 0
(-3135 110);
DISPLAY 0.638298 (-3135 110);
WIRE 16 -1 (-2025 -1100)(-3250 -1100);
FORCEPROP 2 LAST SIG_NAME P5E_CPU1_PE2_TX_C_DN<11>
J 0
(-3135 -1090);
DISPLAY 0.638298 (-3135 -1090);
WIRE 16 -1 (-2025 -900)(-3250 -900);
FORCEPROP 2 LAST SIG_NAME P5E_CPU1_PE3_TX_C_DN<11>
J 0
(-3135 -890);
DISPLAY 0.638298 (-3135 -890);
WIRE 16 -1 (-2025 -1050)(-3250 -1050);
FORCEPROP 2 LAST SIG_NAME P5E_CPU1_PE2_TX_C_DP<11>
J 0
(-3135 -1040);
DISPLAY 0.638298 (-3135 -1040);
WIRE 16 -1 (-2025 -950)(-3250 -950);
FORCEPROP 2 LAST SIG_NAME P5E_CPU1_PE3_TX_C_DP<11>
J 0
(-3135 -940);
DISPLAY 0.638298 (-3135 -940);
WIRE 16 -1 (-2025 -200)(-3250 -200);
FORCEPROP 2 LAST SIG_NAME P5E_CPU1_PE2_TX_C_DP<10>
J 0
(-3135 -190);
DISPLAY 0.638298 (-3135 -190);
WIRE 16 -1 (-2025 -250)(-3250 -250);
FORCEPROP 2 LAST SIG_NAME P5E_CPU1_PE2_TX_C_DN<10>
J 0
(-3135 -240);
DISPLAY 0.638298 (-3135 -240);
WIRE 16 -1 (-2025 1850)(-3250 1850);
FORCEPROP 2 LAST SIG_NAME P5E_CPU1_PE3_RX_DN<8>
J 0
(-3135 1860);
DISPLAY 0.638298 (-3135 1860);
WIRE 16 -1 (-2025 1800)(-3250 1800);
FORCEPROP 2 LAST SIG_NAME P5E_CPU1_PE3_RX_DP<8>
J 0
(-3135 1810);
DISPLAY 0.638298 (-3135 1810);
DOT 1 (-2200 1300);
DOT 1 (-2200 900);
DOT 1 (-2200 600);
DOT 1 (-2200 1750);
DOT 1 (-2200 1600);
DOT 1 (-2200 1450);
DOT 1 (-2200 450);
DOT 1 (-2200 300);
DOT 1 (-2200 150);
DOT 1 (-2200 -300);
DOT 1 (-2200 -150);
DOT 1 (-2200 -700);
DOT 1 (-2200 -1000);
DOT 1 (-2200 -850);
DOT 1 (-2200 -1150);
DOT 1 (-2200 -550);
DOT 1 (-2200 750);
DOT 1 (-2200 0);
DOT 1 (-2200 1050);
DOT 1 (2525 1800);
DOT 1 (2525 1650);
DOT 1 (2525 1500);
DOT 1 (2525 1350);
DOT 1 (2525 1100);
DOT 1 (2525 950);
DOT 1 (2525 800);
DOT 1 (2525 650);
DOT 1 (2525 350);
DOT 1 (2525 500);
DOT 1 (2525 200);
DOT 1 (2525 50);
DOT 1 (2525 -100);
DOT 1 (2525 -250);
DOT 1 (2525 -650);
DOT 1 (2525 -500);
DOT 1 (2525 -800);
DOT 1 (2525 -1100);
DOT 1 (2525 -950);
FORCENOTE
DP/DN SWAP
(-4125 50) 0;
DISPLAY LEFT (-4125 50);
DISPLAY 1.021277 (-4125 50);
FORCENOTE
DP/DN SWAP
(-4125 -250) 0;
DISPLAY LEFT (-4125 -250);
DISPLAY 1.021277 (-4125 -250);
FORCENOTE
DP/DN SWAP
(575 1000) 0;
DISPLAY LEFT (575 1000);
DISPLAY 1.021277 (575 1000);
FORCENOTE
DP/DN SWAP
(575 850) 0;
DISPLAY LEFT (575 850);
DISPLAY 1.021277 (575 850);
FORCENOTE
DP/DN SWAP
(-4150 1675) 0;
DISPLAY LEFT (-4150 1675);
DISPLAY 1.021277 (-4150 1675);
FORCENOTE
DP/DN SWAP
(575 -750) 0;
DISPLAY LEFT (575 -750);
DISPLAY 1.021277 (575 -750);
FORCENOTE
DP/DN SWAP
(-4150 500) 0;
DISPLAY LEFT (-4150 500);
DISPLAY 1.021277 (-4150 500);
FORCENOTE
20210527 MODIFY FOR GT
(-4550 2975) 0;
DISPLAY LEFT (-4550 2975);
DISPLAY 2.510638 (-4550 2975);
PAINT PINK (-4550 2975);
FORCENOTE
DP/DN SWAP
(575 1850) 0;
DISPLAY LEFT (575 1850);
DISPLAY 1.021277 (575 1850);
FORCENOTE
DP/DN SWAP
(575 1725) 0;
DISPLAY LEFT (575 1725);
DISPLAY 1.021277 (575 1725);
FORCENOTE
DP/DN SWAP
(575 1400) 0;
DISPLAY LEFT (575 1400);
DISPLAY 1.021277 (575 1400);
FORCENOTE
DP/DN SWAP
(575 250) 0;
DISPLAY LEFT (575 250);
DISPLAY 1.021277 (575 250);
FORCENOTE
DP/DN SWAP
(575 100) 0;
DISPLAY LEFT (575 100);
DISPLAY 1.021277 (575 100);
FORCENOTE
DP/DN SWAP
(575 550) 0;
DISPLAY LEFT (575 550);
DISPLAY 1.021277 (575 550);
FORCENOTE
DP/DN SWAP
(575 -1025) 0;
DISPLAY LEFT (575 -1025);
DISPLAY 1.021277 (575 -1025);
FORCENOTE
DP/DN SWAP
(575 -600) 0;
DISPLAY LEFT (575 -600);
DISPLAY 1.021277 (575 -600);
FORCENOTE
DP/DN SWAP
(-4150 1350) 0;
DISPLAY LEFT (-4150 1350);
DISPLAY 1.021277 (-4150 1350);
FORCENOTE
DP/DN SWAP
(-4150 825) 0;
DISPLAY LEFT (-4150 825);
DISPLAY 1.021277 (-4150 825);
FORCENOTE
DP/DN SWAP
(-4125 -775) 0;
DISPLAY LEFT (-4125 -775);
DISPLAY 1.021277 (-4125 -775);
FORCENOTE
DP/DN SWAP
(-4125 -1100) 0;
DISPLAY LEFT (-4125 -1100);
DISPLAY 1.021277 (-4125 -1100);
QUIT
